G04 ================== begin FILE IDENTIFICATION RECORD ==================*
G04 Layout Name:  D:/<user>/Wistron_project/16315-1/gbr/16315-1.brd*
G04 Film Name:    DP_REF_L10*
G04 File Format:  Gerber RS274X*
G04 File Origin:  Cadence Allegro 16.5-S056*
G04 Origin Date:  Fri Jun 09 15:33:04 2017*
G04 *
G04 Layer:  BOARD GEOMETRY/DP_REF_L10_TBL*
G04 Layer:  BOARD GEOMETRY/DP_REF_L10_L10*
G04 Layer:  BOARD GEOMETRY/PANEL_OUTLINE*
G04 *
G04 Offset:    (0.00 0.00)*
G04 Mirror:    No*
G04 Mode:      Positive*
G04 Rotation:  0*
G04 FullContactRelief:  No*
G04 UndefLineWidth:     6.00*
G04 ================== end FILE IDENTIFICATION RECORD ====================*
%FSLAX35Y35*MOIN*%
%IR0*IPPOS*OFA0.00000B0.00000*MIA0B0*SFA1.00000B1.00000*%
%ADD10C,.02*%
%ADD11C,.006*%
%ADD12C,.0055*%
%ADD13C,.00425*%
G75*
%LPD*%
G75*
G54D10*
G01X1985143Y1554618D02*
X2825143D01*
G01X1985143Y1519968D02*
X2825143D01*
G01X1985143Y1623918D02*
Y1519968D01*
G01Y1589268D02*
X2825143D01*
G01X1985143Y1623918D02*
X2825143D01*
G01X2160143D02*
Y1519968D01*
G01X2510143Y1623918D02*
Y1519968D01*
G01X2615143Y1623918D02*
Y1519968D01*
G01X2825143Y1623918D02*
Y1519968D01*
G54D11*
G01X6250Y-185556D02*
Y-203056D01*
G01X1228Y-185556D02*
X11272D01*
G01X20038Y-203056D02*
Y-185556D01*
G01Y-194014D02*
X21130Y-192556D01*
X22222Y-191681D01*
X23968Y-191390D01*
X25278Y-191681D01*
X26807Y-192848D01*
X27462Y-194598D01*
Y-203056D01*
G01X41250Y-191390D02*
Y-203056D01*
G01Y-186723D02*
X40813Y-186431D01*
Y-185848D01*
X41250Y-185556D01*
X41687Y-185848D01*
Y-186431D01*
X41250Y-186723D01*
G01X55475Y-201015D02*
X56567Y-202181D01*
X58095Y-203056D01*
X59405D01*
X60715Y-202473D01*
X61588Y-201598D01*
X62025Y-200432D01*
X61807Y-198681D01*
X60933Y-197806D01*
X57003Y-196056D01*
X56130Y-194014D01*
X56567Y-192556D01*
X57440Y-191681D01*
X58750Y-191390D01*
X60060Y-191681D01*
X61370Y-192556D01*
G01X90693Y-207431D02*
X92222Y-208598D01*
X93968Y-208889D01*
X95496Y-208598D01*
X96807Y-207140D01*
X97680Y-205098D01*
Y-191390D01*
G01Y-193723D02*
X96807Y-192556D01*
X95496Y-191681D01*
X93968Y-191390D01*
X92222Y-191973D01*
X91130Y-193139D01*
X90256Y-195181D01*
X89820Y-197223D01*
X90038Y-198973D01*
X90912Y-201015D01*
X92222Y-202473D01*
X93968Y-203056D01*
X95278Y-202764D01*
X96807Y-201598D01*
X97680Y-200432D01*
G01X107975Y-195181D02*
X114962D01*
X114307Y-193139D01*
X113215Y-191973D01*
X111687Y-191390D01*
X110158Y-191681D01*
X108848Y-192556D01*
X107975Y-194598D01*
X107538Y-196348D01*
Y-198098D01*
X107975Y-199848D01*
X109067Y-201598D01*
X110377Y-202764D01*
X111905Y-203056D01*
X113433Y-202473D01*
X114962Y-200723D01*
G01X125693Y-203056D02*
Y-191390D01*
G01Y-193723D02*
X126785Y-192556D01*
X127877Y-191681D01*
X129405Y-191390D01*
X130496Y-191681D01*
X131807Y-192556D01*
G01X142320Y-203056D02*
Y-185556D01*
G01Y-194306D02*
X143412Y-192556D01*
X144722Y-191681D01*
X146032Y-191390D01*
X147996Y-191973D01*
X149307Y-193139D01*
X150180Y-195181D01*
Y-197514D01*
X149743Y-199848D01*
X148870Y-201598D01*
X147342Y-202764D01*
X146032Y-203056D01*
X144722Y-202764D01*
X143412Y-201890D01*
X142320Y-200432D01*
G01X160475Y-195181D02*
X167462D01*
X166807Y-193139D01*
X165715Y-191973D01*
X164187Y-191390D01*
X162658Y-191681D01*
X161348Y-192556D01*
X160475Y-194598D01*
X160038Y-196348D01*
Y-198098D01*
X160475Y-199848D01*
X161567Y-201598D01*
X162877Y-202764D01*
X164405Y-203056D01*
X165933Y-202473D01*
X167462Y-200723D01*
G01X178193Y-203056D02*
Y-191390D01*
G01Y-193723D02*
X179285Y-192556D01*
X180377Y-191681D01*
X181905Y-191390D01*
X182996Y-191681D01*
X184307Y-192556D01*
G01X216250Y-191390D02*
Y-203056D01*
G01Y-186723D02*
X215813Y-186431D01*
Y-185848D01*
X216250Y-185556D01*
X216687Y-185848D01*
Y-186431D01*
X216250Y-186723D01*
G01X230475Y-201015D02*
X231567Y-202181D01*
X233095Y-203056D01*
X234405D01*
X235715Y-202473D01*
X236588Y-201598D01*
X237025Y-200432D01*
X236807Y-198681D01*
X235933Y-197806D01*
X232003Y-196056D01*
X231130Y-194014D01*
X231567Y-192556D01*
X232440Y-191681D01*
X233750Y-191390D01*
X235060Y-191681D01*
X236370Y-192556D01*
G01X265256Y-207431D02*
X266785Y-208598D01*
X268095Y-208889D01*
X269842Y-208306D01*
X271152Y-206848D01*
X271807Y-204222D01*
Y-191390D01*
G01Y-186723D02*
X271370Y-186431D01*
Y-185848D01*
X271807Y-185556D01*
X272243Y-185848D01*
Y-186431D01*
X271807Y-186723D01*
G01X282538Y-191390D02*
Y-199556D01*
X283412Y-201598D01*
X284722Y-202764D01*
X286250Y-203056D01*
X287778Y-202764D01*
X289088Y-201598D01*
X289962Y-199556D01*
G01Y-203056D02*
Y-191390D01*
G01X300475Y-201015D02*
X301567Y-202181D01*
X303095Y-203056D01*
X304405D01*
X305715Y-202473D01*
X306588Y-201598D01*
X307025Y-200432D01*
X306807Y-198681D01*
X305933Y-197806D01*
X302003Y-196056D01*
X301130Y-194014D01*
X301567Y-192556D01*
X302440Y-191681D01*
X303750Y-191390D01*
X305060Y-191681D01*
X306370Y-192556D01*
G01X321250Y-185556D02*
Y-203056D01*
G01X318193Y-191390D02*
X324307D01*
G01X354940Y-203056D02*
Y-188181D01*
X355377Y-186723D01*
X356250Y-185848D01*
X357560Y-185556D01*
X358870Y-186139D01*
X359525Y-187598D01*
G01X356905Y-192556D02*
X352538D01*
G01X373750Y-203056D02*
X372440Y-202764D01*
X371130Y-201598D01*
X370256Y-199556D01*
X369820Y-197223D01*
X370256Y-194889D01*
X371130Y-192848D01*
X372440Y-191681D01*
X373750Y-191390D01*
X375060Y-191681D01*
X376370Y-192848D01*
X377243Y-194889D01*
X377462Y-197223D01*
X377243Y-199556D01*
X376370Y-201598D01*
X375060Y-202764D01*
X373750Y-203056D01*
G01X388193D02*
Y-191390D01*
G01Y-193723D02*
X389285Y-192556D01*
X390377Y-191681D01*
X391905Y-191390D01*
X392996Y-191681D01*
X394307Y-192556D01*
G01X421665Y-208306D02*
X422975Y-208889D01*
X424722Y-208306D01*
X425813Y-207140D01*
X426687Y-205681D01*
X427996Y-201015D01*
X430835Y-191390D01*
G01X423848D02*
X427996Y-201015D01*
G01X443750Y-203056D02*
X442440Y-202764D01*
X441130Y-201598D01*
X440256Y-199556D01*
X439820Y-197223D01*
X440256Y-194889D01*
X441130Y-192848D01*
X442440Y-191681D01*
X443750Y-191390D01*
X445060Y-191681D01*
X446370Y-192848D01*
X447243Y-194889D01*
X447462Y-197223D01*
X447243Y-199556D01*
X446370Y-201598D01*
X445060Y-202764D01*
X443750Y-203056D01*
G01X457538Y-191390D02*
Y-199556D01*
X458412Y-201598D01*
X459722Y-202764D01*
X461250Y-203056D01*
X462778Y-202764D01*
X464088Y-201598D01*
X464962Y-199556D01*
G01Y-203056D02*
Y-191390D01*
G01X475693Y-203056D02*
Y-191390D01*
G01Y-193723D02*
X476785Y-192556D01*
X477877Y-191681D01*
X479405Y-191390D01*
X480496Y-191681D01*
X481807Y-192556D01*
G01X510693Y-203056D02*
Y-191390D01*
G01Y-193723D02*
X511785Y-192556D01*
X512877Y-191681D01*
X514405Y-191390D01*
X515496Y-191681D01*
X516807Y-192556D01*
G01X527975Y-195181D02*
X534962D01*
X534307Y-193139D01*
X533215Y-191973D01*
X531687Y-191390D01*
X530158Y-191681D01*
X528848Y-192556D01*
X527975Y-194598D01*
X527538Y-196348D01*
Y-198098D01*
X527975Y-199848D01*
X529067Y-201598D01*
X530377Y-202764D01*
X531905Y-203056D01*
X533433Y-202473D01*
X534962Y-200723D01*
G01X547440Y-203056D02*
Y-188181D01*
X547877Y-186723D01*
X548750Y-185848D01*
X550060Y-185556D01*
X551370Y-186139D01*
X552025Y-187598D01*
G01X549405Y-192556D02*
X545038D01*
G01X562975Y-195181D02*
X569962D01*
X569307Y-193139D01*
X568215Y-191973D01*
X566687Y-191390D01*
X565158Y-191681D01*
X563848Y-192556D01*
X562975Y-194598D01*
X562538Y-196348D01*
Y-198098D01*
X562975Y-199848D01*
X564067Y-201598D01*
X565377Y-202764D01*
X566905Y-203056D01*
X568433Y-202473D01*
X569962Y-200723D01*
G01X580693Y-203056D02*
Y-191390D01*
G01Y-193723D02*
X581785Y-192556D01*
X582877Y-191681D01*
X584405Y-191390D01*
X585496Y-191681D01*
X586807Y-192556D01*
G01X597975Y-195181D02*
X604962D01*
X604307Y-193139D01*
X603215Y-191973D01*
X601687Y-191390D01*
X600158Y-191681D01*
X598848Y-192556D01*
X597975Y-194598D01*
X597538Y-196348D01*
Y-198098D01*
X597975Y-199848D01*
X599067Y-201598D01*
X600377Y-202764D01*
X601905Y-203056D01*
X603433Y-202473D01*
X604962Y-200723D01*
G01X615038Y-203056D02*
Y-191390D01*
G01Y-194306D02*
X615912Y-192848D01*
X617222Y-191681D01*
X618968Y-191390D01*
X620496Y-191681D01*
X621807Y-192848D01*
X622462Y-194889D01*
Y-203056D01*
G01X639743Y-192848D02*
X638215Y-191681D01*
X636905Y-191390D01*
X635158Y-191973D01*
X633848Y-193139D01*
X632975Y-195181D01*
X632756Y-197223D01*
X632975Y-199265D01*
X633848Y-201015D01*
X635158Y-202473D01*
X636905Y-203056D01*
X638433Y-202473D01*
X639743Y-201306D01*
G01X650475Y-195181D02*
X657462D01*
X656807Y-193139D01*
X655715Y-191973D01*
X654187Y-191390D01*
X652658Y-191681D01*
X651348Y-192556D01*
X650475Y-194598D01*
X650038Y-196348D01*
Y-198098D01*
X650475Y-199848D01*
X651567Y-201598D01*
X652877Y-202764D01*
X654405Y-203056D01*
X655933Y-202473D01*
X657462Y-200723D01*
G01X688750Y-185556D02*
Y-203056D01*
G01X685693Y-191390D02*
X691807D01*
G01X706250Y-203056D02*
X704940Y-202764D01*
X703630Y-201598D01*
X702756Y-199556D01*
X702320Y-197223D01*
X702756Y-194889D01*
X703630Y-192848D01*
X704940Y-191681D01*
X706250Y-191390D01*
X707560Y-191681D01*
X708870Y-192848D01*
X709743Y-194889D01*
X709962Y-197223D01*
X709743Y-199556D01*
X708870Y-201598D01*
X707560Y-202764D01*
X706250Y-203056D01*
G01X739940D02*
Y-188181D01*
X740377Y-186723D01*
X741250Y-185848D01*
X742560Y-185556D01*
X743870Y-186139D01*
X744525Y-187598D01*
G01X741905Y-192556D02*
X737538D01*
G01X758750Y-191390D02*
Y-203056D01*
G01Y-186723D02*
X758313Y-186431D01*
Y-185848D01*
X758750Y-185556D01*
X759187Y-185848D01*
Y-186431D01*
X758750Y-186723D01*
G01X772538Y-203056D02*
Y-191390D01*
G01Y-194306D02*
X773412Y-192848D01*
X774722Y-191681D01*
X776468Y-191390D01*
X777996Y-191681D01*
X779307Y-192848D01*
X779962Y-194889D01*
Y-203056D01*
G01X797680Y-185556D02*
Y-203056D01*
G01Y-200432D02*
X796807Y-201890D01*
X795496Y-202764D01*
X793968Y-203056D01*
X792222Y-202473D01*
X790912Y-201015D01*
X790038Y-199265D01*
X789820Y-197223D01*
X790038Y-195181D01*
X790912Y-193431D01*
X792222Y-191973D01*
X793968Y-191390D01*
X795496Y-191681D01*
X796588Y-192265D01*
X797680Y-193431D01*
G01X828750Y-185556D02*
Y-203056D01*
G01X825693Y-191390D02*
X831807D01*
G01X842538Y-203056D02*
Y-185556D01*
G01Y-194014D02*
X843630Y-192556D01*
X844722Y-191681D01*
X846468Y-191390D01*
X847778Y-191681D01*
X849307Y-192848D01*
X849962Y-194598D01*
Y-203056D01*
G01X860475Y-195181D02*
X867462D01*
X866807Y-193139D01*
X865715Y-191973D01*
X864187Y-191390D01*
X862658Y-191681D01*
X861348Y-192556D01*
X860475Y-194598D01*
X860038Y-196348D01*
Y-198098D01*
X860475Y-199848D01*
X861567Y-201598D01*
X862877Y-202764D01*
X864405Y-203056D01*
X865933Y-202473D01*
X867462Y-200723D01*
G01X893947Y-203056D02*
Y-185556D01*
X898313D01*
X900060Y-186431D01*
X901370Y-187598D01*
X902462Y-189347D01*
X903335Y-191390D01*
X903553Y-194306D01*
X903335Y-197223D01*
X902462Y-199265D01*
X901370Y-201015D01*
X900060Y-202181D01*
X898313Y-203056D01*
X893947D01*
G01X911883D02*
Y-185556D01*
X917123D01*
X918870Y-186431D01*
X920180Y-188473D01*
X920617Y-190806D01*
X920180Y-193139D01*
X919088Y-194889D01*
X917123Y-195765D01*
X911883D01*
G01X951250Y-191390D02*
Y-203056D01*
G01Y-186723D02*
X950813Y-186431D01*
Y-185848D01*
X951250Y-185556D01*
X951687Y-185848D01*
Y-186431D01*
X951250Y-186723D01*
G01X962200Y-203056D02*
Y-191390D01*
G01Y-194598D02*
X962855Y-193139D01*
X963947Y-191973D01*
X965475Y-191390D01*
X967003Y-191973D01*
X968095Y-193139D01*
X968750Y-194598D01*
Y-203056D01*
G01Y-194598D02*
X969405Y-193139D01*
X970496Y-191973D01*
X972025Y-191390D01*
X973553Y-191973D01*
X974645Y-193139D01*
X975300Y-194889D01*
Y-203056D01*
G01X982320Y-208889D02*
Y-191390D01*
G01Y-194014D02*
X983412Y-192556D01*
X984503Y-191681D01*
X986250Y-191390D01*
X987778Y-191681D01*
X989307Y-193139D01*
X989962Y-195181D01*
X990180Y-197223D01*
X989962Y-199265D01*
X989307Y-201306D01*
X987996Y-202473D01*
X986250Y-203056D01*
X984722Y-202764D01*
X983193Y-201890D01*
X982320Y-200723D01*
G01X1000475Y-195181D02*
X1007462D01*
X1006807Y-193139D01*
X1005715Y-191973D01*
X1004187Y-191390D01*
X1002658Y-191681D01*
X1001348Y-192556D01*
X1000475Y-194598D01*
X1000038Y-196348D01*
Y-198098D01*
X1000475Y-199848D01*
X1001567Y-201598D01*
X1002877Y-202764D01*
X1004405Y-203056D01*
X1005933Y-202473D01*
X1007462Y-200723D01*
G01X1025180Y-185556D02*
Y-203056D01*
G01Y-200432D02*
X1024307Y-201890D01*
X1022996Y-202764D01*
X1021468Y-203056D01*
X1019722Y-202473D01*
X1018412Y-201015D01*
X1017538Y-199265D01*
X1017320Y-197223D01*
X1017538Y-195181D01*
X1018412Y-193431D01*
X1019722Y-191973D01*
X1021468Y-191390D01*
X1022996Y-191681D01*
X1024088Y-192265D01*
X1025180Y-193431D01*
G01X1042680Y-203056D02*
Y-191390D01*
G01Y-193431D02*
X1041807Y-192265D01*
X1040496Y-191681D01*
X1038968Y-191390D01*
X1037440Y-191973D01*
X1036130Y-193139D01*
X1035256Y-194889D01*
X1034820Y-197223D01*
X1035256Y-199556D01*
X1036130Y-201306D01*
X1037440Y-202473D01*
X1038968Y-203056D01*
X1040496Y-202764D01*
X1041807Y-201890D01*
X1042680Y-200723D01*
G01X1052538Y-203056D02*
Y-191390D01*
G01Y-194306D02*
X1053412Y-192848D01*
X1054722Y-191681D01*
X1056468Y-191390D01*
X1057996Y-191681D01*
X1059307Y-192848D01*
X1059962Y-194889D01*
Y-203056D01*
G01X1077243Y-192848D02*
X1075715Y-191681D01*
X1074405Y-191390D01*
X1072658Y-191973D01*
X1071348Y-193139D01*
X1070475Y-195181D01*
X1070256Y-197223D01*
X1070475Y-199265D01*
X1071348Y-201015D01*
X1072658Y-202473D01*
X1074405Y-203056D01*
X1075933Y-202473D01*
X1077243Y-201306D01*
G01X1087975Y-195181D02*
X1094962D01*
X1094307Y-193139D01*
X1093215Y-191973D01*
X1091687Y-191390D01*
X1090158Y-191681D01*
X1088848Y-192556D01*
X1087975Y-194598D01*
X1087538Y-196348D01*
Y-198098D01*
X1087975Y-199848D01*
X1089067Y-201598D01*
X1090377Y-202764D01*
X1091905Y-203056D01*
X1093433Y-202473D01*
X1094962Y-200723D01*
G01X1126250Y-185556D02*
Y-203056D01*
G01X1123193Y-191390D02*
X1129307D01*
G01X1140693Y-203056D02*
Y-191390D01*
G01Y-193723D02*
X1141785Y-192556D01*
X1142877Y-191681D01*
X1144405Y-191390D01*
X1145496Y-191681D01*
X1146807Y-192556D01*
G01X1165180Y-203056D02*
Y-191390D01*
G01Y-193431D02*
X1164307Y-192265D01*
X1162996Y-191681D01*
X1161468Y-191390D01*
X1159940Y-191973D01*
X1158630Y-193139D01*
X1157756Y-194889D01*
X1157320Y-197223D01*
X1157756Y-199556D01*
X1158630Y-201306D01*
X1159940Y-202473D01*
X1161468Y-203056D01*
X1162996Y-202764D01*
X1164307Y-201890D01*
X1165180Y-200723D01*
G01X1182243Y-192848D02*
X1180715Y-191681D01*
X1179405Y-191390D01*
X1177658Y-191973D01*
X1176348Y-193139D01*
X1175475Y-195181D01*
X1175256Y-197223D01*
X1175475Y-199265D01*
X1176348Y-201015D01*
X1177658Y-202473D01*
X1179405Y-203056D01*
X1180933Y-202473D01*
X1182243Y-201306D01*
G01X1192975Y-195181D02*
X1199962D01*
X1199307Y-193139D01*
X1198215Y-191973D01*
X1196687Y-191390D01*
X1195158Y-191681D01*
X1193848Y-192556D01*
X1192975Y-194598D01*
X1192538Y-196348D01*
Y-198098D01*
X1192975Y-199848D01*
X1194067Y-201598D01*
X1195377Y-202764D01*
X1196905Y-203056D01*
X1198433Y-202473D01*
X1199962Y-200723D01*
G01X1210475Y-201015D02*
X1211567Y-202181D01*
X1213095Y-203056D01*
X1214405D01*
X1215715Y-202473D01*
X1216588Y-201598D01*
X1217025Y-200432D01*
X1216807Y-198681D01*
X1215933Y-197806D01*
X1212003Y-196056D01*
X1211130Y-194014D01*
X1211567Y-192556D01*
X1212440Y-191681D01*
X1213750Y-191390D01*
X1215060Y-191681D01*
X1216370Y-192556D01*
G01X1248750Y-191390D02*
Y-203056D01*
G01Y-186723D02*
X1248313Y-186431D01*
Y-185848D01*
X1248750Y-185556D01*
X1249187Y-185848D01*
Y-186431D01*
X1248750Y-186723D01*
G01X1262538Y-203056D02*
Y-191390D01*
G01Y-194306D02*
X1263412Y-192848D01*
X1264722Y-191681D01*
X1266468Y-191390D01*
X1267996Y-191681D01*
X1269307Y-192848D01*
X1269962Y-194889D01*
Y-203056D01*
G01X1301250D02*
Y-185556D01*
G01X1322680Y-203056D02*
Y-191390D01*
G01Y-193431D02*
X1321807Y-192265D01*
X1320496Y-191681D01*
X1318968Y-191390D01*
X1317440Y-191973D01*
X1316130Y-193139D01*
X1315256Y-194889D01*
X1314820Y-197223D01*
X1315256Y-199556D01*
X1316130Y-201306D01*
X1317440Y-202473D01*
X1318968Y-203056D01*
X1320496Y-202764D01*
X1321807Y-201890D01*
X1322680Y-200723D01*
G01X1331665Y-208306D02*
X1332975Y-208889D01*
X1334722Y-208306D01*
X1335813Y-207140D01*
X1336687Y-205681D01*
X1337996Y-201015D01*
X1340835Y-191390D01*
G01X1333848D02*
X1337996Y-201015D01*
G01X1350475Y-195181D02*
X1357462D01*
X1356807Y-193139D01*
X1355715Y-191973D01*
X1354187Y-191390D01*
X1352658Y-191681D01*
X1351348Y-192556D01*
X1350475Y-194598D01*
X1350038Y-196348D01*
Y-198098D01*
X1350475Y-199848D01*
X1351567Y-201598D01*
X1352877Y-202764D01*
X1354405Y-203056D01*
X1355933Y-202473D01*
X1357462Y-200723D01*
G01X1368193Y-203056D02*
Y-191390D01*
G01Y-193723D02*
X1369285Y-192556D01*
X1370377Y-191681D01*
X1371905Y-191390D01*
X1372996Y-191681D01*
X1374307Y-192556D01*
G01X1401883Y-185556D02*
Y-203056D01*
X1410617D01*
G01X1423750D02*
Y-185556D01*
X1421130Y-189056D01*
G01Y-203056D02*
X1426370D01*
G01X1441250Y-185556D02*
X1439503Y-186139D01*
X1438193Y-187598D01*
X1437320Y-189347D01*
X1436665Y-191681D01*
X1436447Y-194306D01*
X1436665Y-196931D01*
X1437320Y-199265D01*
X1438193Y-201015D01*
X1439503Y-202473D01*
X1441250Y-203056D01*
X1442996Y-202473D01*
X1444307Y-201015D01*
X1445180Y-199265D01*
X1445835Y-196931D01*
X1446053Y-194306D01*
X1445835Y-191681D01*
X1445180Y-189347D01*
X1444307Y-187598D01*
X1442996Y-186139D01*
X1441250Y-185556D01*
G01X1458750Y-203639D02*
X1458313Y-203348D01*
Y-202764D01*
X1458750Y-202473D01*
X1459187Y-202764D01*
Y-203348D01*
X1458750Y-203639D01*
G01X2008773Y1616518D02*
X2014013D01*
G01X2011393D02*
Y1599018D01*
G01X2008773D02*
X2014013D01*
G01X2023216D02*
Y1616518D01*
X2028893Y1601935D01*
X2034570Y1616518D01*
Y1599018D01*
G01X2042026D02*
Y1616518D01*
X2047266D01*
X2049013Y1615643D01*
X2050323Y1613601D01*
X2050760Y1611268D01*
X2050323Y1608935D01*
X2049231Y1607185D01*
X2047266Y1606309D01*
X2042026D01*
G01X2062801Y1593185D02*
X2060618Y1596101D01*
X2059526Y1599018D01*
Y1610684D01*
X2060618Y1613601D01*
X2062801Y1616518D01*
G01X2081393Y1599018D02*
X2079646Y1599310D01*
X2078118Y1600476D01*
X2076808Y1602226D01*
X2075934Y1604268D01*
X2075498Y1606601D01*
Y1608935D01*
X2075934Y1611268D01*
X2076808Y1613310D01*
X2078118Y1615059D01*
X2079646Y1616226D01*
X2081393Y1616518D01*
X2083139Y1616226D01*
X2084668Y1615059D01*
X2085978Y1613310D01*
X2086852Y1611268D01*
X2087288Y1608935D01*
Y1606601D01*
X2086852Y1604268D01*
X2085978Y1602226D01*
X2084668Y1600476D01*
X2083139Y1599310D01*
X2081393Y1599018D01*
G01X2095181D02*
Y1616518D01*
G01Y1608060D02*
X2096273Y1609518D01*
X2097365Y1610393D01*
X2099111Y1610684D01*
X2100421Y1610393D01*
X2101950Y1609226D01*
X2102605Y1607476D01*
Y1599018D01*
G01X2109843D02*
Y1610684D01*
G01Y1607476D02*
X2110498Y1608935D01*
X2111590Y1610101D01*
X2113118Y1610684D01*
X2114646Y1610101D01*
X2115738Y1608935D01*
X2116393Y1607476D01*
Y1599018D01*
G01Y1607476D02*
X2117048Y1608935D01*
X2118139Y1610101D01*
X2119668Y1610684D01*
X2121196Y1610101D01*
X2122288Y1608935D01*
X2122943Y1607185D01*
Y1599018D01*
G01X2134985Y1593185D02*
X2137168Y1596101D01*
X2138260Y1599018D01*
Y1610684D01*
X2137168Y1613601D01*
X2134985Y1616518D01*
G01X1986890Y1633668D02*
Y1651168D01*
X1991256D01*
X1993003Y1650293D01*
X1994313Y1649126D01*
X1995405Y1647377D01*
X1996278Y1645334D01*
X1996496Y1642418D01*
X1996278Y1639501D01*
X1995405Y1637459D01*
X1994313Y1635709D01*
X1993003Y1634543D01*
X1991256Y1633668D01*
X1986890D01*
G01X2004826D02*
Y1651168D01*
X2010066D01*
X2011813Y1650293D01*
X2013123Y1648251D01*
X2013560Y1645918D01*
X2013123Y1643585D01*
X2012031Y1641835D01*
X2010066Y1640959D01*
X2004826D01*
G01X2041573Y1651168D02*
X2046813D01*
G01X2044193D02*
Y1633668D01*
G01X2041573D02*
X2046813D01*
G01X2056016D02*
Y1651168D01*
X2061693Y1636585D01*
X2067370Y1651168D01*
Y1633668D01*
G01X2074826D02*
Y1651168D01*
X2080066D01*
X2081813Y1650293D01*
X2083123Y1648251D01*
X2083560Y1645918D01*
X2083123Y1643585D01*
X2082031Y1641835D01*
X2080066Y1640959D01*
X2074826D01*
G01X2101060Y1633668D02*
X2092326D01*
Y1651168D01*
X2101060D01*
G01X2097566Y1642710D02*
X2092326D01*
G01X2109390Y1633668D02*
Y1651168D01*
X2113756D01*
X2115503Y1650293D01*
X2116813Y1649126D01*
X2117905Y1647377D01*
X2118778Y1645334D01*
X2118996Y1642418D01*
X2118778Y1639501D01*
X2117905Y1637459D01*
X2116813Y1635709D01*
X2115503Y1634543D01*
X2113756Y1633668D01*
X2109390D01*
G01X2126234D02*
X2131693Y1651168D01*
X2137152Y1633668D01*
G01X2135186Y1639793D02*
X2128199D01*
G01X2144171Y1633668D02*
Y1651168D01*
X2154215Y1633668D01*
Y1651168D01*
G01X2171496Y1649709D02*
X2170186Y1650585D01*
X2168658Y1651168D01*
X2166911D01*
X2164946Y1650293D01*
X2163418Y1648835D01*
X2162326Y1647084D01*
X2161453Y1644168D01*
X2161234Y1641543D01*
X2161671Y1638918D01*
X2162326Y1637168D01*
X2163636Y1635418D01*
X2165165Y1634251D01*
X2166693Y1633668D01*
X2168221D01*
X2169750Y1634251D01*
X2171060Y1635126D01*
X2172152Y1636292D01*
G01X2188560Y1633668D02*
X2179826D01*
Y1651168D01*
X2188560D01*
G01X2185066Y1642710D02*
X2179826D01*
G01X2219193Y1651168D02*
Y1633668D01*
G01X2214171Y1651168D02*
X2224215D01*
G01X2231234Y1633668D02*
X2236693Y1651168D01*
X2242152Y1633668D01*
G01X2240186Y1639793D02*
X2233199D01*
G01X2255939Y1643001D02*
X2256813Y1643876D01*
X2257468Y1645334D01*
X2257905Y1647377D01*
X2257468Y1649126D01*
X2256595Y1650293D01*
X2255066Y1651168D01*
X2249171D01*
Y1633668D01*
X2256376D01*
X2257905Y1634834D01*
X2258778Y1636585D01*
X2259215Y1638626D01*
X2258778Y1640668D01*
X2257468Y1642418D01*
X2255939Y1643001D01*
X2249171D01*
G01X2267326Y1651168D02*
Y1633668D01*
X2276060D01*
G01X2293560D02*
X2284826D01*
Y1651168D01*
X2293560D01*
G01X2290066Y1642710D02*
X2284826D01*
G01X2306693Y1633085D02*
X2306256Y1633376D01*
Y1633960D01*
X2306693Y1634251D01*
X2307130Y1633960D01*
Y1633376D01*
X2306693Y1633085D01*
G01Y1640959D02*
X2306256Y1641251D01*
Y1641835D01*
X2306693Y1642126D01*
X2307130Y1641835D01*
Y1641251D01*
X2306693Y1640959D01*
G01X2337326Y1651168D02*
Y1633668D01*
X2346060D01*
G01X2359193D02*
Y1651168D01*
X2356573Y1647668D01*
G01Y1633668D02*
X2361813D01*
G01X2376693Y1651168D02*
X2374946Y1650585D01*
X2373636Y1649126D01*
X2372763Y1647377D01*
X2372108Y1645043D01*
X2371890Y1642418D01*
X2372108Y1639793D01*
X2372763Y1637459D01*
X2373636Y1635709D01*
X2374946Y1634251D01*
X2376693Y1633668D01*
X2378439Y1634251D01*
X2379750Y1635709D01*
X2380623Y1637459D01*
X2381278Y1639793D01*
X2381496Y1642418D01*
X2381278Y1645043D01*
X2380623Y1647377D01*
X2379750Y1649126D01*
X2378439Y1650585D01*
X2376693Y1651168D01*
G01X2046393Y1564368D02*
X2047921Y1564660D01*
X2049668Y1565534D01*
X2050760Y1566992D01*
X2051196Y1569035D01*
X2050760Y1571076D01*
X2049450Y1572826D01*
X2047485Y1573701D01*
X2045301D01*
X2043991Y1574285D01*
X2042899Y1575743D01*
X2042463Y1577784D01*
X2043118Y1579826D01*
X2044646Y1581285D01*
X2046393Y1581868D01*
X2048139Y1581285D01*
X2049668Y1579826D01*
X2050323Y1577784D01*
X2049886Y1575743D01*
X2048795Y1574285D01*
X2047485Y1573701D01*
X2045301D01*
X2043336Y1572826D01*
X2042026Y1571076D01*
X2041590Y1569035D01*
X2042026Y1566992D01*
X2043118Y1565534D01*
X2044865Y1564660D01*
X2046393Y1564368D01*
G01X2059090Y1566992D02*
X2060399Y1565534D01*
X2061928Y1564660D01*
X2063893Y1564368D01*
X2065858Y1564951D01*
X2067386Y1566118D01*
X2068478Y1568159D01*
X2068696Y1570493D01*
X2068260Y1572826D01*
X2067168Y1574285D01*
X2065639Y1575451D01*
X2064111Y1575743D01*
X2062583Y1575451D01*
X2060618Y1574285D01*
X2061273Y1581868D01*
X2067168D01*
G01X2081393Y1563785D02*
X2080956Y1564076D01*
Y1564660D01*
X2081393Y1564951D01*
X2081830Y1564660D01*
Y1564076D01*
X2081393Y1563785D01*
G01X2098893Y1581868D02*
X2097146Y1581285D01*
X2095836Y1579826D01*
X2094963Y1578077D01*
X2094308Y1575743D01*
X2094090Y1573118D01*
X2094308Y1570493D01*
X2094963Y1568159D01*
X2095836Y1566409D01*
X2097146Y1564951D01*
X2098893Y1564368D01*
X2100639Y1564951D01*
X2101950Y1566409D01*
X2102823Y1568159D01*
X2103478Y1570493D01*
X2103696Y1573118D01*
X2103478Y1575743D01*
X2102823Y1578077D01*
X2101950Y1579826D01*
X2100639Y1581285D01*
X2098893Y1581868D01*
G01X2037643Y1529718D02*
Y1547218D01*
X2035023Y1543718D01*
G01Y1529718D02*
X2040263D01*
G01X2055143Y1547218D02*
X2053396Y1546635D01*
X2052086Y1545176D01*
X2051213Y1543427D01*
X2050558Y1541093D01*
X2050340Y1538468D01*
X2050558Y1535843D01*
X2051213Y1533509D01*
X2052086Y1531759D01*
X2053396Y1530301D01*
X2055143Y1529718D01*
X2056889Y1530301D01*
X2058200Y1531759D01*
X2059073Y1533509D01*
X2059728Y1535843D01*
X2059946Y1538468D01*
X2059728Y1541093D01*
X2059073Y1543427D01*
X2058200Y1545176D01*
X2056889Y1546635D01*
X2055143Y1547218D01*
G01X2072643D02*
X2070896Y1546635D01*
X2069586Y1545176D01*
X2068713Y1543427D01*
X2068058Y1541093D01*
X2067840Y1538468D01*
X2068058Y1535843D01*
X2068713Y1533509D01*
X2069586Y1531759D01*
X2070896Y1530301D01*
X2072643Y1529718D01*
X2074389Y1530301D01*
X2075700Y1531759D01*
X2076573Y1533509D01*
X2077228Y1535843D01*
X2077446Y1538468D01*
X2077228Y1541093D01*
X2076573Y1543427D01*
X2075700Y1545176D01*
X2074389Y1546635D01*
X2072643Y1547218D01*
G01X2090143Y1529135D02*
X2089706Y1529426D01*
Y1530010D01*
X2090143Y1530301D01*
X2090580Y1530010D01*
Y1529426D01*
X2090143Y1529135D01*
G01X2107643Y1547218D02*
X2105896Y1546635D01*
X2104586Y1545176D01*
X2103713Y1543427D01*
X2103058Y1541093D01*
X2102840Y1538468D01*
X2103058Y1535843D01*
X2103713Y1533509D01*
X2104586Y1531759D01*
X2105896Y1530301D01*
X2107643Y1529718D01*
X2109389Y1530301D01*
X2110700Y1531759D01*
X2111573Y1533509D01*
X2112228Y1535843D01*
X2112446Y1538468D01*
X2112228Y1541093D01*
X2111573Y1543427D01*
X2110700Y1545176D01*
X2109389Y1546635D01*
X2107643Y1547218D01*
G01X2241093Y1616518D02*
X2244149Y1599018D01*
X2247643Y1616518D01*
X2251136Y1599018D01*
X2254193Y1616518D01*
G01X2262523D02*
X2267763D01*
G01X2265143D02*
Y1599018D01*
G01X2262523D02*
X2267763D01*
G01X2277840D02*
Y1616518D01*
X2282206D01*
X2283953Y1615643D01*
X2285263Y1614476D01*
X2286355Y1612727D01*
X2287228Y1610684D01*
X2287446Y1607768D01*
X2287228Y1604851D01*
X2286355Y1602809D01*
X2285263Y1601059D01*
X2283953Y1599893D01*
X2282206Y1599018D01*
X2277840D01*
G01X2300143Y1616518D02*
Y1599018D01*
G01X2295121Y1616518D02*
X2305165D01*
G01X2313058Y1599018D02*
Y1616518D01*
G01X2322228D02*
Y1599018D01*
G01Y1607768D02*
X2313058D01*
G01X2334051Y1593185D02*
X2331868Y1596101D01*
X2330776Y1599018D01*
Y1610684D01*
X2331868Y1613601D01*
X2334051Y1616518D01*
G01X2346093Y1599018D02*
Y1610684D01*
G01Y1607476D02*
X2346748Y1608935D01*
X2347840Y1610101D01*
X2349368Y1610684D01*
X2350896Y1610101D01*
X2351988Y1608935D01*
X2352643Y1607476D01*
Y1599018D01*
G01Y1607476D02*
X2353298Y1608935D01*
X2354389Y1610101D01*
X2355918Y1610684D01*
X2357446Y1610101D01*
X2358538Y1608935D01*
X2359193Y1607185D01*
Y1599018D01*
G01X2370143Y1610684D02*
Y1599018D01*
G01Y1615351D02*
X2369706Y1615643D01*
Y1616226D01*
X2370143Y1616518D01*
X2370580Y1616226D01*
Y1615643D01*
X2370143Y1615351D01*
G01X2387643Y1599018D02*
Y1616518D01*
G01X2401868Y1601059D02*
X2402960Y1599893D01*
X2404488Y1599018D01*
X2405798D01*
X2407108Y1599601D01*
X2407981Y1600476D01*
X2408418Y1601642D01*
X2408200Y1603393D01*
X2407326Y1604268D01*
X2403396Y1606018D01*
X2402523Y1608060D01*
X2402960Y1609518D01*
X2403833Y1610393D01*
X2405143Y1610684D01*
X2406453Y1610393D01*
X2407763Y1609518D01*
G01X2423735Y1593185D02*
X2425918Y1596101D01*
X2427010Y1599018D01*
Y1610684D01*
X2425918Y1613601D01*
X2423735Y1616518D01*
G01X2277840Y1566992D02*
X2279149Y1565534D01*
X2280678Y1564660D01*
X2282643Y1564368D01*
X2284608Y1564951D01*
X2286136Y1566118D01*
X2287228Y1568159D01*
X2287446Y1570493D01*
X2287010Y1572826D01*
X2285918Y1574285D01*
X2284389Y1575451D01*
X2282861Y1575743D01*
X2281333Y1575451D01*
X2279368Y1574285D01*
X2280023Y1581868D01*
X2285918D01*
G01X2300143Y1563785D02*
X2299706Y1564076D01*
Y1564660D01*
X2300143Y1564951D01*
X2300580Y1564660D01*
Y1564076D01*
X2300143Y1563785D01*
G01X2312840Y1566992D02*
X2314149Y1565534D01*
X2315678Y1564660D01*
X2317643Y1564368D01*
X2319608Y1564951D01*
X2321136Y1566118D01*
X2322228Y1568159D01*
X2322446Y1570493D01*
X2322010Y1572826D01*
X2320918Y1574285D01*
X2319389Y1575451D01*
X2317861Y1575743D01*
X2316333Y1575451D01*
X2314368Y1574285D01*
X2315023Y1581868D01*
X2320918D01*
G01X2331213Y1563785D02*
X2339073Y1581868D01*
G01X2348495Y1571659D02*
X2350023Y1573701D01*
X2351333Y1574868D01*
X2353080Y1575451D01*
X2354608Y1574868D01*
X2355700Y1573701D01*
X2356573Y1571951D01*
X2356791Y1569910D01*
X2356573Y1568159D01*
X2355700Y1566409D01*
X2354389Y1564951D01*
X2352861Y1564368D01*
X2351115Y1564951D01*
X2349586Y1566701D01*
X2348713Y1569326D01*
X2348495Y1572243D01*
X2348931Y1576034D01*
X2349586Y1578077D01*
X2350678Y1580118D01*
X2352206Y1581576D01*
X2353735Y1581868D01*
X2355263Y1581285D01*
X2356355Y1579826D01*
G01X2370143Y1563785D02*
X2369706Y1564076D01*
Y1564660D01*
X2370143Y1564951D01*
X2370580Y1564660D01*
Y1564076D01*
X2370143Y1563785D01*
G01X2387643Y1581868D02*
X2385896Y1581285D01*
X2384586Y1579826D01*
X2383713Y1578077D01*
X2383058Y1575743D01*
X2382840Y1573118D01*
X2383058Y1570493D01*
X2383713Y1568159D01*
X2384586Y1566409D01*
X2385896Y1564951D01*
X2387643Y1564368D01*
X2389389Y1564951D01*
X2390700Y1566409D01*
X2391573Y1568159D01*
X2392228Y1570493D01*
X2392446Y1573118D01*
X2392228Y1575743D01*
X2391573Y1578077D01*
X2390700Y1579826D01*
X2389389Y1581285D01*
X2387643Y1581868D01*
G01X2267763Y1529718D02*
Y1547218D01*
X2259684Y1534676D01*
X2270602D01*
G01X2282643Y1529135D02*
X2282206Y1529426D01*
Y1530010D01*
X2282643Y1530301D01*
X2283080Y1530010D01*
Y1529426D01*
X2282643Y1529135D01*
G01X2295995Y1544301D02*
X2297305Y1546051D01*
X2298833Y1546926D01*
X2300580Y1547218D01*
X2302763Y1546635D01*
X2304291Y1545176D01*
X2304728Y1543427D01*
X2304510Y1541676D01*
X2303636Y1540218D01*
X2299270Y1537301D01*
X2297305Y1535260D01*
X2295995Y1532342D01*
X2295558Y1529718D01*
X2304728D01*
G01X2312840Y1532342D02*
X2314149Y1530884D01*
X2315678Y1530010D01*
X2317643Y1529718D01*
X2319608Y1530301D01*
X2321136Y1531468D01*
X2322228Y1533509D01*
X2322446Y1535843D01*
X2322010Y1538176D01*
X2320918Y1539635D01*
X2319389Y1540801D01*
X2317861Y1541093D01*
X2316333Y1540801D01*
X2314368Y1539635D01*
X2315023Y1547218D01*
X2320918D01*
G01X2331213Y1529135D02*
X2339073Y1547218D01*
G01X2352643Y1529718D02*
X2354171Y1530010D01*
X2355918Y1530884D01*
X2357010Y1532342D01*
X2357446Y1534385D01*
X2357010Y1536426D01*
X2355700Y1538176D01*
X2353735Y1539051D01*
X2351551D01*
X2350241Y1539635D01*
X2349149Y1541093D01*
X2348713Y1543134D01*
X2349368Y1545176D01*
X2350896Y1546635D01*
X2352643Y1547218D01*
X2354389Y1546635D01*
X2355918Y1545176D01*
X2356573Y1543134D01*
X2356136Y1541093D01*
X2355045Y1539635D01*
X2353735Y1539051D01*
X2351551D01*
X2349586Y1538176D01*
X2348276Y1536426D01*
X2347840Y1534385D01*
X2348276Y1532342D01*
X2349368Y1530884D01*
X2351115Y1530010D01*
X2352643Y1529718D01*
G01X2370143Y1529135D02*
X2369706Y1529426D01*
Y1530010D01*
X2370143Y1530301D01*
X2370580Y1530010D01*
Y1529426D01*
X2370143Y1529135D01*
G01X2387206Y1529718D02*
X2387643Y1533509D01*
X2388298Y1536718D01*
X2389171Y1539635D01*
X2390263Y1542843D01*
X2392010Y1547218D01*
X2383276D01*
G01X2400340Y1532342D02*
X2401649Y1530884D01*
X2403178Y1530010D01*
X2405143Y1529718D01*
X2407108Y1530301D01*
X2408636Y1531468D01*
X2409728Y1533509D01*
X2409946Y1535843D01*
X2409510Y1538176D01*
X2408418Y1539635D01*
X2406889Y1540801D01*
X2405361Y1541093D01*
X2403833Y1540801D01*
X2401868Y1539635D01*
X2402523Y1547218D01*
X2408418D01*
G01X2536393Y1616518D02*
Y1599018D01*
G01X2531371Y1616518D02*
X2541415D01*
G01X2553893Y1599018D02*
Y1606893D01*
X2549526Y1616518D01*
G01X2558260D02*
X2553893Y1606893D01*
G01X2567026Y1599018D02*
Y1616518D01*
X2572266D01*
X2574013Y1615643D01*
X2575323Y1613601D01*
X2575760Y1611268D01*
X2575323Y1608935D01*
X2574231Y1607185D01*
X2572266Y1606309D01*
X2567026D01*
G01X2593260Y1599018D02*
X2584526D01*
Y1616518D01*
X2593260D01*
G01X2589766Y1608060D02*
X2584526D01*
G01X2549090Y1564368D02*
Y1581868D01*
X2553456D01*
X2555203Y1580993D01*
X2556513Y1579826D01*
X2557605Y1578077D01*
X2558478Y1576034D01*
X2558696Y1573118D01*
X2558478Y1570201D01*
X2557605Y1568159D01*
X2556513Y1566409D01*
X2555203Y1565243D01*
X2553456Y1564368D01*
X2549090D01*
G01X2567026D02*
Y1581868D01*
X2572266D01*
X2574013Y1580993D01*
X2575323Y1578951D01*
X2575760Y1576618D01*
X2575323Y1574285D01*
X2574231Y1572535D01*
X2572266Y1571659D01*
X2567026D01*
G01X2549090Y1529718D02*
Y1547218D01*
X2553456D01*
X2555203Y1546343D01*
X2556513Y1545176D01*
X2557605Y1543427D01*
X2558478Y1541384D01*
X2558696Y1538468D01*
X2558478Y1535551D01*
X2557605Y1533509D01*
X2556513Y1531759D01*
X2555203Y1530593D01*
X2553456Y1529718D01*
X2549090D01*
G01X2567026D02*
Y1547218D01*
X2572266D01*
X2574013Y1546343D01*
X2575323Y1544301D01*
X2575760Y1541968D01*
X2575323Y1539635D01*
X2574231Y1537885D01*
X2572266Y1537009D01*
X2567026D01*
G01X2637026Y1599018D02*
Y1616518D01*
X2642485D01*
X2644231Y1615643D01*
X2645323Y1614476D01*
X2645760Y1612143D01*
X2645323Y1609809D01*
X2644013Y1608351D01*
X2642485Y1607476D01*
X2637026D01*
G01X2642485D02*
X2645760Y1599018D01*
G01X2655618Y1606893D02*
X2662605D01*
X2661950Y1608935D01*
X2660858Y1610101D01*
X2659330Y1610684D01*
X2657801Y1610393D01*
X2656491Y1609518D01*
X2655618Y1607476D01*
X2655181Y1605726D01*
Y1603976D01*
X2655618Y1602226D01*
X2656710Y1600476D01*
X2658020Y1599310D01*
X2659548Y1599018D01*
X2661076Y1599601D01*
X2662605Y1601351D01*
G01X2675083Y1599018D02*
Y1613893D01*
X2675520Y1615351D01*
X2676393Y1616226D01*
X2677703Y1616518D01*
X2679013Y1615935D01*
X2679668Y1614476D01*
G01X2677048Y1609518D02*
X2672681D01*
G01X2693893Y1598435D02*
X2693456Y1598726D01*
Y1599310D01*
X2693893Y1599601D01*
X2694330Y1599310D01*
Y1598726D01*
X2693893Y1598435D01*
G01X2724526Y1599018D02*
Y1616518D01*
X2729766D01*
X2731513Y1615643D01*
X2732823Y1613601D01*
X2733260Y1611268D01*
X2732823Y1608935D01*
X2731731Y1607185D01*
X2729766Y1606309D01*
X2724526D01*
G01X2746393Y1599018D02*
Y1616518D01*
G01X2767823Y1599018D02*
Y1610684D01*
G01Y1608643D02*
X2766950Y1609809D01*
X2765639Y1610393D01*
X2764111Y1610684D01*
X2762583Y1610101D01*
X2761273Y1608935D01*
X2760399Y1607185D01*
X2759963Y1604851D01*
X2760399Y1602518D01*
X2761273Y1600768D01*
X2762583Y1599601D01*
X2764111Y1599018D01*
X2765639Y1599310D01*
X2766950Y1600184D01*
X2767823Y1601351D01*
G01X2777681Y1599018D02*
Y1610684D01*
G01Y1607768D02*
X2778555Y1609226D01*
X2779865Y1610393D01*
X2781611Y1610684D01*
X2783139Y1610393D01*
X2784450Y1609226D01*
X2785105Y1607185D01*
Y1599018D01*
G01X2795618Y1606893D02*
X2802605D01*
X2801950Y1608935D01*
X2800858Y1610101D01*
X2799330Y1610684D01*
X2797801Y1610393D01*
X2796491Y1609518D01*
X2795618Y1607476D01*
X2795181Y1605726D01*
Y1603976D01*
X2795618Y1602226D01*
X2796710Y1600476D01*
X2798020Y1599310D01*
X2799548Y1599018D01*
X2801076Y1599601D01*
X2802605Y1601351D01*
G01X2672026Y1581868D02*
Y1564368D01*
X2680760D01*
G01X2690181Y1566409D02*
X2691710Y1564951D01*
X2693456Y1564368D01*
X2695203Y1564951D01*
X2696731Y1566701D01*
X2697823Y1569326D01*
X2698260Y1571951D01*
Y1575159D01*
X2697823Y1577784D01*
X2696731Y1580118D01*
X2695421Y1581285D01*
X2693893Y1581868D01*
X2692146Y1581285D01*
X2690836Y1580118D01*
X2689963Y1578368D01*
X2689526Y1576034D01*
X2689963Y1573993D01*
X2691055Y1571951D01*
X2692365Y1570784D01*
X2693893Y1570493D01*
X2695639Y1571076D01*
X2696950Y1572535D01*
X2698260Y1575159D01*
G01X2707463Y1563785D02*
X2715323Y1581868D01*
G01X2724526D02*
Y1564368D01*
X2733260D01*
G01X2746393D02*
Y1581868D01*
X2743773Y1578368D01*
G01Y1564368D02*
X2749013D01*
G01X2763893D02*
Y1581868D01*
X2761273Y1578368D01*
G01Y1564368D02*
X2766513D01*
G01X2672026Y1547218D02*
Y1529718D01*
X2680760D01*
G01X2690181Y1531759D02*
X2691710Y1530301D01*
X2693456Y1529718D01*
X2695203Y1530301D01*
X2696731Y1532051D01*
X2697823Y1534676D01*
X2698260Y1537301D01*
Y1540509D01*
X2697823Y1543134D01*
X2696731Y1545468D01*
X2695421Y1546635D01*
X2693893Y1547218D01*
X2692146Y1546635D01*
X2690836Y1545468D01*
X2689963Y1543718D01*
X2689526Y1541384D01*
X2689963Y1539343D01*
X2691055Y1537301D01*
X2692365Y1536134D01*
X2693893Y1535843D01*
X2695639Y1536426D01*
X2696950Y1537885D01*
X2698260Y1540509D01*
G01X2707463Y1529135D02*
X2715323Y1547218D01*
G01X2724526D02*
Y1529718D01*
X2733260D01*
G01X2746393D02*
Y1547218D01*
X2743773Y1543718D01*
G01Y1529718D02*
X2749013D01*
G01X2763893D02*
Y1547218D01*
X2761273Y1543718D01*
G01Y1529718D02*
X2766513D01*
G01X2916693Y1576034D02*
Y1564368D01*
G01Y1580701D02*
X2916256Y1580993D01*
Y1581576D01*
X2916693Y1581868D01*
X2917130Y1581576D01*
Y1580993D01*
X2916693Y1580701D01*
G01X2930918Y1566409D02*
X2932010Y1565243D01*
X2933538Y1564368D01*
X2934848D01*
X2936158Y1564951D01*
X2937031Y1565826D01*
X2937468Y1566992D01*
X2937250Y1568743D01*
X2936376Y1569618D01*
X2932446Y1571368D01*
X2931573Y1573410D01*
X2932010Y1574868D01*
X2932883Y1575743D01*
X2934193Y1576034D01*
X2935503Y1575743D01*
X2936813Y1574868D01*
G01X2964171Y1564368D02*
Y1581868D01*
X2974215Y1564368D01*
Y1581868D01*
G01X2986693Y1564368D02*
X2984946Y1564660D01*
X2983418Y1565826D01*
X2982108Y1567576D01*
X2981234Y1569618D01*
X2980798Y1571951D01*
Y1574285D01*
X2981234Y1576618D01*
X2982108Y1578660D01*
X2983418Y1580409D01*
X2984946Y1581576D01*
X2986693Y1581868D01*
X2988439Y1581576D01*
X2989968Y1580409D01*
X2991278Y1578660D01*
X2992152Y1576618D01*
X2992588Y1574285D01*
Y1571951D01*
X2992152Y1569618D01*
X2991278Y1567576D01*
X2989968Y1565826D01*
X2988439Y1564660D01*
X2986693Y1564368D01*
G01X3004193Y1581868D02*
Y1564368D01*
G01X2999171Y1581868D02*
X3009215D01*
G01X3035481Y1576034D02*
Y1567868D01*
X3036355Y1565826D01*
X3037665Y1564660D01*
X3039193Y1564368D01*
X3040721Y1564660D01*
X3042031Y1565826D01*
X3042905Y1567868D01*
G01Y1564368D02*
Y1576034D01*
G01X3053418Y1566409D02*
X3054510Y1565243D01*
X3056038Y1564368D01*
X3057348D01*
X3058658Y1564951D01*
X3059531Y1565826D01*
X3059968Y1566992D01*
X3059750Y1568743D01*
X3058876Y1569618D01*
X3054946Y1571368D01*
X3054073Y1573410D01*
X3054510Y1574868D01*
X3055383Y1575743D01*
X3056693Y1576034D01*
X3058003Y1575743D01*
X3059313Y1574868D01*
G01X3070918Y1572243D02*
X3077905D01*
X3077250Y1574285D01*
X3076158Y1575451D01*
X3074630Y1576034D01*
X3073101Y1575743D01*
X3071791Y1574868D01*
X3070918Y1572826D01*
X3070481Y1571076D01*
Y1569326D01*
X3070918Y1567576D01*
X3072010Y1565826D01*
X3073320Y1564660D01*
X3074848Y1564368D01*
X3076376Y1564951D01*
X3077905Y1566701D01*
G01X3095623Y1581868D02*
Y1564368D01*
G01Y1566992D02*
X3094750Y1565534D01*
X3093439Y1564660D01*
X3091911Y1564368D01*
X3090165Y1564951D01*
X3088855Y1566409D01*
X3087981Y1568159D01*
X3087763Y1570201D01*
X3087981Y1572243D01*
X3088855Y1573993D01*
X3090165Y1575451D01*
X3091911Y1576034D01*
X3093439Y1575743D01*
X3094531Y1575159D01*
X3095623Y1573993D01*
G01X2841890Y1598435D02*
X2851496Y1611268D01*
G01X2846693Y1613601D02*
Y1596101D01*
G01X2851496Y1598435D02*
X2841890Y1611268D01*
G01X2840143Y1604851D02*
X2853243D01*
G01X2878855D02*
X2884531D01*
G01X2911890Y1599018D02*
Y1616518D01*
X2916256D01*
X2918003Y1615643D01*
X2919313Y1614476D01*
X2920405Y1612727D01*
X2921278Y1610684D01*
X2921496Y1607768D01*
X2921278Y1604851D01*
X2920405Y1602809D01*
X2919313Y1601059D01*
X2918003Y1599893D01*
X2916256Y1599018D01*
X2911890D01*
G01X2930918Y1606893D02*
X2937905D01*
X2937250Y1608935D01*
X2936158Y1610101D01*
X2934630Y1610684D01*
X2933101Y1610393D01*
X2931791Y1609518D01*
X2930918Y1607476D01*
X2930481Y1605726D01*
Y1603976D01*
X2930918Y1602226D01*
X2932010Y1600476D01*
X2933320Y1599310D01*
X2934848Y1599018D01*
X2936376Y1599601D01*
X2937905Y1601351D01*
G01X2947981Y1599018D02*
Y1610684D01*
G01Y1607768D02*
X2948855Y1609226D01*
X2950165Y1610393D01*
X2951911Y1610684D01*
X2953439Y1610393D01*
X2954750Y1609226D01*
X2955405Y1607185D01*
Y1599018D01*
G01X2969193D02*
X2967883Y1599310D01*
X2966573Y1600476D01*
X2965699Y1602518D01*
X2965263Y1604851D01*
X2965699Y1607185D01*
X2966573Y1609226D01*
X2967883Y1610393D01*
X2969193Y1610684D01*
X2970503Y1610393D01*
X2971813Y1609226D01*
X2972686Y1607185D01*
X2972905Y1604851D01*
X2972686Y1602518D01*
X2971813Y1600476D01*
X2970503Y1599310D01*
X2969193Y1599018D01*
G01X2986693Y1616518D02*
Y1599018D01*
G01X2983636Y1610684D02*
X2989750D01*
G01X3000918Y1606893D02*
X3007905D01*
X3007250Y1608935D01*
X3006158Y1610101D01*
X3004630Y1610684D01*
X3003101Y1610393D01*
X3001791Y1609518D01*
X3000918Y1607476D01*
X3000481Y1605726D01*
Y1603976D01*
X3000918Y1602226D01*
X3002010Y1600476D01*
X3003320Y1599310D01*
X3004848Y1599018D01*
X3006376Y1599601D01*
X3007905Y1601351D01*
G01X3018418Y1601059D02*
X3019510Y1599893D01*
X3021038Y1599018D01*
X3022348D01*
X3023658Y1599601D01*
X3024531Y1600476D01*
X3024968Y1601642D01*
X3024750Y1603393D01*
X3023876Y1604268D01*
X3019946Y1606018D01*
X3019073Y1608060D01*
X3019510Y1609518D01*
X3020383Y1610393D01*
X3021693Y1610684D01*
X3023003Y1610393D01*
X3024313Y1609518D01*
G01X3056693Y1616518D02*
Y1599018D01*
G01X3053636Y1610684D02*
X3059750D01*
G01X3070481Y1599018D02*
Y1616518D01*
G01Y1608060D02*
X3071573Y1609518D01*
X3072665Y1610393D01*
X3074411Y1610684D01*
X3075721Y1610393D01*
X3077250Y1609226D01*
X3077905Y1607476D01*
Y1599018D01*
G01X3095623D02*
Y1610684D01*
G01Y1608643D02*
X3094750Y1609809D01*
X3093439Y1610393D01*
X3091911Y1610684D01*
X3090383Y1610101D01*
X3089073Y1608935D01*
X3088199Y1607185D01*
X3087763Y1604851D01*
X3088199Y1602518D01*
X3089073Y1600768D01*
X3090383Y1599601D01*
X3091911Y1599018D01*
X3093439Y1599310D01*
X3094750Y1600184D01*
X3095623Y1601351D01*
G01X3109193Y1616518D02*
Y1599018D01*
G01X3106136Y1610684D02*
X3112250D01*
G01X3144193Y1616518D02*
Y1599018D01*
G01X3141136Y1610684D02*
X3147250D01*
G01X3157981Y1599018D02*
Y1616518D01*
G01Y1608060D02*
X3159073Y1609518D01*
X3160165Y1610393D01*
X3161911Y1610684D01*
X3163221Y1610393D01*
X3164750Y1609226D01*
X3165405Y1607476D01*
Y1599018D01*
G01X3179193Y1610684D02*
Y1599018D01*
G01Y1615351D02*
X3178756Y1615643D01*
Y1616226D01*
X3179193Y1616518D01*
X3179630Y1616226D01*
Y1615643D01*
X3179193Y1615351D01*
G01X3193418Y1601059D02*
X3194510Y1599893D01*
X3196038Y1599018D01*
X3197348D01*
X3198658Y1599601D01*
X3199531Y1600476D01*
X3199968Y1601642D01*
X3199750Y1603393D01*
X3198876Y1604268D01*
X3194946Y1606018D01*
X3194073Y1608060D01*
X3194510Y1609518D01*
X3195383Y1610393D01*
X3196693Y1610684D01*
X3198003Y1610393D01*
X3199313Y1609518D01*
G01X3229073Y1616518D02*
X3234313D01*
G01X3231693D02*
Y1599018D01*
G01X3229073D02*
X3234313D01*
G01X3242643D02*
Y1610684D01*
G01Y1607476D02*
X3243298Y1608935D01*
X3244390Y1610101D01*
X3245918Y1610684D01*
X3247446Y1610101D01*
X3248538Y1608935D01*
X3249193Y1607476D01*
Y1599018D01*
G01Y1607476D02*
X3249848Y1608935D01*
X3250939Y1610101D01*
X3252468Y1610684D01*
X3253996Y1610101D01*
X3255088Y1608935D01*
X3255743Y1607185D01*
Y1599018D01*
G01X3262763Y1593185D02*
Y1610684D01*
G01Y1608060D02*
X3263855Y1609518D01*
X3264946Y1610393D01*
X3266693Y1610684D01*
X3268221Y1610393D01*
X3269750Y1608935D01*
X3270405Y1606893D01*
X3270623Y1604851D01*
X3270405Y1602809D01*
X3269750Y1600768D01*
X3268439Y1599601D01*
X3266693Y1599018D01*
X3265165Y1599310D01*
X3263636Y1600184D01*
X3262763Y1601351D01*
G01X3280918Y1606893D02*
X3287905D01*
X3287250Y1608935D01*
X3286158Y1610101D01*
X3284630Y1610684D01*
X3283101Y1610393D01*
X3281791Y1609518D01*
X3280918Y1607476D01*
X3280481Y1605726D01*
Y1603976D01*
X3280918Y1602226D01*
X3282010Y1600476D01*
X3283320Y1599310D01*
X3284848Y1599018D01*
X3286376Y1599601D01*
X3287905Y1601351D01*
G01X3305623Y1616518D02*
Y1599018D01*
G01Y1601642D02*
X3304750Y1600184D01*
X3303439Y1599310D01*
X3301911Y1599018D01*
X3300165Y1599601D01*
X3298855Y1601059D01*
X3297981Y1602809D01*
X3297763Y1604851D01*
X3297981Y1606893D01*
X3298855Y1608643D01*
X3300165Y1610101D01*
X3301911Y1610684D01*
X3303439Y1610393D01*
X3304531Y1609809D01*
X3305623Y1608643D01*
G01X3323123Y1599018D02*
Y1610684D01*
G01Y1608643D02*
X3322250Y1609809D01*
X3320939Y1610393D01*
X3319411Y1610684D01*
X3317883Y1610101D01*
X3316573Y1608935D01*
X3315699Y1607185D01*
X3315263Y1604851D01*
X3315699Y1602518D01*
X3316573Y1600768D01*
X3317883Y1599601D01*
X3319411Y1599018D01*
X3320939Y1599310D01*
X3322250Y1600184D01*
X3323123Y1601351D01*
G01X3332981Y1599018D02*
Y1610684D01*
G01Y1607768D02*
X3333855Y1609226D01*
X3335165Y1610393D01*
X3336911Y1610684D01*
X3338439Y1610393D01*
X3339750Y1609226D01*
X3340405Y1607185D01*
Y1599018D01*
G01X3357686Y1609226D02*
X3356158Y1610393D01*
X3354848Y1610684D01*
X3353101Y1610101D01*
X3351791Y1608935D01*
X3350918Y1606893D01*
X3350699Y1604851D01*
X3350918Y1602809D01*
X3351791Y1601059D01*
X3353101Y1599601D01*
X3354848Y1599018D01*
X3356376Y1599601D01*
X3357686Y1600768D01*
G01X3368418Y1606893D02*
X3375405D01*
X3374750Y1608935D01*
X3373658Y1610101D01*
X3372130Y1610684D01*
X3370601Y1610393D01*
X3369291Y1609518D01*
X3368418Y1607476D01*
X3367981Y1605726D01*
Y1603976D01*
X3368418Y1602226D01*
X3369510Y1600476D01*
X3370820Y1599310D01*
X3372348Y1599018D01*
X3373876Y1599601D01*
X3375405Y1601351D01*
G01X0Y-137756D02*
G03X15000Y-152756I15000J0D01*
G01X0Y-137756D02*
G03X15000Y-152756I15000J0D01*
G01X0Y-11811D02*
Y-137756D01*
G01Y-11811D02*
Y-137756D01*
G01X854331Y-152756D02*
X15000D01*
G01X854331D02*
X15000D01*
G01X23622Y-7874D02*
G03Y0I0J3937D01*
G01Y-7874D02*
G03Y0I0J3937D01*
G01X0Y3937D02*
G03X3937Y0I3937J0D01*
G01Y-7874D02*
X23622D01*
G01X0Y3937D02*
G03X3937Y0I3937J0D01*
G01Y-7874D02*
X23622D01*
G01X3937D02*
G03X0Y-11811I0J-3937D01*
G01X3937Y-7874D02*
G03X0Y-11811I0J-3937D01*
G01X3937Y0D02*
X397638D01*
G01X3937D02*
X397638D01*
G01X0Y1370866D02*
Y3937D01*
G01Y1370866D02*
Y3937D01*
G01X3937Y1374803D02*
G03X0Y1370866I0J-3937D01*
G01X3937Y1374803D02*
G03X0Y1370866I0J-3937D01*
G01X23622Y1374803D02*
G03Y1382677I0J3937D01*
G01Y1374803D02*
G03Y1382677I0J3937D01*
G01X3937D02*
X23622D01*
G01X0Y1386614D02*
G03X3937Y1382677I3937J0D01*
G01D02*
X23622D01*
G01X0Y1386614D02*
G03X3937Y1382677I3937J0D01*
G01Y1374803D02*
X746850D01*
G01D02*
X3937D01*
G01X0Y1386614D02*
Y1643268D01*
G01Y1386614D02*
Y1643268D01*
G01X15000Y1658268D02*
G03X0Y1643268I0J-15000D01*
G01X15000Y1658268D02*
G03X0Y1643268I0J-15000D01*
G01X775591Y1658268D02*
X15000D01*
G01X775591D02*
X15000D01*
G01X54331Y-7874D02*
X323228D01*
G01X54331D02*
X323228D01*
G01X54331Y0D02*
G03Y-7874I0J-3937D01*
G01Y0D02*
G03Y-7874I0J-3937D01*
G01Y1382677D02*
G03Y1374803I0J-3937D01*
G01Y1382677D02*
G03Y1374803I0J-3937D01*
G01Y1382677D02*
X353740D01*
G01X54331D02*
X353740D01*
G01X114295Y378885D02*
G03X148106I16905J-13531D01*
G01X114295D02*
G03X148106I16905J-13531D01*
G01X114295D02*
G03X121220Y392016I-30737J24602D01*
G01X114295Y378885D02*
G03X121220Y392016I-30737J24602D01*
G01X114295Y831641D02*
G03X121220Y844772I-30737J24601D01*
G01X114295Y831641D02*
G03X121220Y844772I-30737J24602D01*
G01X114295Y831641D02*
G03X148106I16905J-13531D01*
G01X114295D02*
G03X148106I16905J-13531D01*
G01X114295Y1284397D02*
G03X148106I16905J-13531D01*
G01X114295D02*
G03X148106I16905J-13531D01*
G01X114295D02*
G03X121220Y1297528I-30737J24601D01*
G01X114295Y1284397D02*
G03X121220Y1297528I-30737J24602D01*
G01X141181Y392016D02*
G03X121220I-9980J-3039D01*
G01X141181D02*
G03X148106Y378885I37662J11471D01*
G01X141181Y392016D02*
G03X121220I-9980J-3039D01*
G01X141181D02*
G03X148106Y378885I37662J11471D01*
G01X141181Y844772D02*
G03X148106Y831641I37662J11471D01*
G01X141181Y844772D02*
G03X148106Y831641I37662J11471D01*
G01X141181Y844772D02*
G03X121220I-9980J-3040D01*
G01X141181D02*
G03X121220I-9980J-3039D01*
G01X141181Y1297528D02*
G03X121220I-9980J-3040D01*
G01X141181D02*
G03X148106Y1284397I37662J11471D01*
G01X141181Y1297528D02*
G03X121220I-9980J-3040D01*
G01X141181D02*
G03X148106Y1284397I37662J11471D01*
G01X323228Y-7874D02*
G03Y0I0J3937D01*
G01Y-7874D02*
G03Y0I0J3937D01*
G01X362598D02*
G03Y-7874I0J-3937D01*
G01Y0D02*
G03Y-7874I0J-3937D01*
G01X362327Y378885D02*
G03X396138I16905J-13531D01*
G01X362327D02*
G03X396138I16905J-13531D01*
G01X362327D02*
G03X369252Y392016I-30737J24602D01*
G01X362327Y378885D02*
G03X369252Y392016I-30737J24602D01*
G01X362327Y831641D02*
G03X369252Y844772I-30737J24602D01*
G01X362327Y831641D02*
G03X369252Y844772I-30737J24602D01*
G01X362327Y831641D02*
G03X396138I16905J-13531D01*
G01X362327D02*
G03X396138I16905J-13531D01*
G01X362327Y1284397D02*
G03X396138I16905J-13531D01*
G01X362327D02*
G03X396138I16905J-13531D01*
G01X362327D02*
G03X369252Y1297528I-30737J24602D01*
G01X362327Y1284397D02*
G03X369252Y1297528I-30737J24602D01*
G01X353740Y1374803D02*
G03Y1382677I0J3937D01*
G01Y1374803D02*
G03Y1382677I0J3937D01*
G01X401575Y3937D02*
Y55118D01*
G01X397638Y0D02*
G03X401575Y3937I0J3937D01*
G01X409449D02*
Y51181D01*
G01X397638Y-7874D02*
G03X409449Y3937I0J11811D01*
G01X397638Y0D02*
G03X401575Y3937I0J3937D01*
G01D02*
Y55118D01*
G01X409449Y3937D02*
Y51181D01*
G01X397638Y-7874D02*
G03X409449Y3937I0J11811D01*
G01X362598Y-7874D02*
X397638D01*
G01X362598D02*
X397638D01*
G01X405512Y59055D02*
G03X401575Y55118I0J-3937D01*
G01X405512Y59055D02*
G03X401575Y55118I0J-3937D01*
G01X405512Y59055D02*
X586614D01*
G01X409449Y51181D02*
X582677D01*
G01X405512Y59055D02*
X586614D01*
G01X409449Y51181D02*
X582677D01*
G01X389213Y392016D02*
G03X396138Y378885I37662J11471D01*
G01X389213Y392016D02*
G03X396138Y378885I37662J11471D01*
G01X389213Y392016D02*
G03X369252I-9981J-3039D01*
G01X389213D02*
G03X369252I-9981J-3039D01*
G01X389213Y844772D02*
G03X396138Y831641I37662J11471D01*
G01X389213Y844772D02*
G03X396138Y831641I37662J11471D01*
G01X389213Y844772D02*
G03X369252I-9981J-3040D01*
G01X389213D02*
G03X369252I-9981J-3039D01*
G01X389213Y1297528D02*
G03X396138Y1284397I37662J11471D01*
G01X389213Y1297528D02*
G03X396138Y1284397I37662J11471D01*
G01X389213Y1297528D02*
G03X369252I-9981J-3040D01*
G01X389213D02*
G03X369252I-9981J-3040D01*
G01X393110Y1382677D02*
G03Y1374803I0J-3937D01*
G01Y1382677D02*
X692520D01*
G01X393110D02*
X692520D01*
G01X393110D02*
G03Y1374803I0J-3937D01*
G01X523327Y829921D02*
G03X483169I-20079J0D01*
G01X523327D02*
G03I-20079J0D01*
G01X483169D02*
G03X523327I20079J0D01*
G01X594488Y-7874D02*
X628765D01*
G01X594488D02*
X628765D01*
G01X590551Y55118D02*
Y3937D01*
G01D02*
G03X594488Y0I3937J0D01*
G01X582677Y51181D02*
Y3937D01*
G01D02*
G03X594488Y-7874I11811J0D01*
G01X590551Y55118D02*
Y3937D01*
G01D02*
G03X594488Y0I3937J0D01*
G01X582677Y51181D02*
Y3937D01*
G01D02*
G03X594488Y-7874I11811J0D01*
G01Y0D02*
X783465D01*
G01X594488D02*
X783465D01*
G01X590551Y55118D02*
G03X586614Y59055I-3937J0D01*
G01X590551Y55118D02*
G03X586614Y59055I-3937J0D01*
G01X628765Y-7874D02*
G03Y0I0J3937D01*
G01Y-7874D02*
G03Y0I0J3937D01*
G01X610358Y378885D02*
G03X644169I16906J-13531D01*
G01X610358D02*
G03X644169I16906J-13531D01*
G01X637244Y392016D02*
G03X644169Y378885I37662J11471D01*
G01X637244Y392016D02*
G03X644169Y378885I37662J11471D01*
G01X637244Y392016D02*
G03X617283I-9980J-3039D01*
G01X637244D02*
G03X617283I-9980J-3039D01*
G01X610358Y378885D02*
G03X617283Y392016I-30737J24602D01*
G01X610358Y378885D02*
G03X617283Y392016I-30737J24602D01*
G01X637244Y844772D02*
G03X644169Y831641I37662J11471D01*
G01X637244Y844772D02*
G03X644169Y831641I37662J11471D01*
G01X610358D02*
G03X617283Y844772I-30737J24601D01*
G01X610358Y831641D02*
G03X617283Y844772I-30737J24602D01*
G01X610358Y831641D02*
G03X644169I16906J-13531D01*
G01X610358D02*
G03X644169I16906J-13531D01*
G01X637244Y844772D02*
G03X617283I-9980J-3040D01*
G01X637244D02*
G03X617283I-9980J-3039D01*
G01X610358Y1284397D02*
G03X644169I16906J-13531D01*
G01X610358D02*
G03X644169I16906J-13531D01*
G01X637244Y1297528D02*
G03X644169Y1284397I37662J11471D01*
G01X637244Y1297528D02*
G03X644169Y1284397I37662J11471D01*
G01X610358D02*
G03X617283Y1297528I-30737J24601D01*
G01X637244D02*
G03X617283I-9980J-3040D01*
G01X610358Y1284397D02*
G03X617283Y1297528I-30737J24602D01*
G01X637244D02*
G03X617283I-9980J-3040D01*
G01X659474Y0D02*
G03Y-7874I0J-3937D01*
G01Y0D02*
G03Y-7874I0J-3937D01*
G01D02*
X780203D01*
G01X659474D02*
X780203D01*
G01X692520Y1374803D02*
G03Y1382677I0J3937D01*
G01Y1374803D02*
G03Y1382677I0J3937D01*
G01X746850Y1374803D02*
G03X750787Y1378740I0J3937D01*
G01X746850Y1374803D02*
G03X750787Y1378740I0J3937D01*
G01X723228Y1382677D02*
G03Y1374803I0J-3937D01*
G01Y1382677D02*
X742913D01*
G01X723228D02*
X742913D01*
G01X723228D02*
G03Y1374803I0J-3937D01*
G01X742913Y1464567D02*
Y1382677D01*
G01Y1464567D02*
Y1382677D01*
G01X754724Y1476378D02*
G03X742913Y1464567I0J-11811D01*
G01X754724Y1476378D02*
G03X742913Y1464567I0J-11811D01*
G01X862205Y-7874D02*
X791339D01*
G01X787402Y-3937D02*
G03X791339Y-7874I3937J0D01*
G01X787402Y-3937D02*
G03X791339Y-7874I3937J0D01*
G01D02*
X862205D01*
G01X858268Y-15748D02*
X791339D01*
G01X858268D02*
X791339D01*
G01X787402Y-3937D02*
G03X783465Y0I-3937J0D01*
G01X787402Y-3937D02*
G03X783465Y0I-3937J0D01*
G01X780203Y-7874D02*
G03X791339Y-15748I11136J3937D01*
G01X780203Y-7874D02*
G03X791339Y-15748I11136J3937D01*
G01X779551Y264712D02*
G03X813362I16905J-13531D01*
G01X779551D02*
G03X813362I16905J-13531D01*
G01X779551D02*
G03X786476Y277843I-30737J24601D01*
G01X806437D02*
G03X786476I-9981J-3040D01*
G01X779551Y264712D02*
G03X786476Y277843I-30737J24602D01*
G01X806437D02*
G03X786476I-9981J-3040D01*
G01X779551Y737153D02*
G03X786476Y750284I-30737J24601D01*
G01X779551Y737154D02*
G03X786476Y750284I-30736J24602D01*
G01X779551Y737153D02*
G03X813362I16905J-13531D01*
G01X779551D02*
G03X813362I16905J-13531D01*
G01X806437Y750284D02*
G03X786476I-9981J-3040D01*
G01X806437D02*
G03X786476I-9981J-3040D01*
G01X750787Y1464567D02*
Y1378740D01*
G01Y1464567D02*
Y1378740D01*
G01X783465Y1468504D02*
G03X787402Y1472441I0J3937D01*
G01X783465Y1468504D02*
G03X787402Y1472441I0J3937D01*
G01X783465Y1468504D02*
X754724D01*
G01D02*
G03X750787Y1464567I0J-3937D01*
G01X783465Y1468504D02*
X754724D01*
G01D02*
G03X750787Y1464567I0J-3937D01*
G01X779528Y1476378D02*
X754724D01*
G01X779528D02*
X754724D01*
G01X787402Y1654331D02*
Y1472441D01*
G01X779528Y1596063D02*
Y1476378D01*
G01X787402Y1654331D02*
Y1472441D01*
G01X779528Y1596063D02*
Y1476378D01*
G01X787402Y1596063D02*
G03X779528I-3937J0D01*
G01X787402D02*
G03X779528I-3937J0D01*
G01X1216535Y1658268D02*
X791339D01*
G01D02*
G03X787402Y1654331I0J-3937D01*
G01X779528D02*
G03X775591Y1658268I-3937J0D01*
G01X1216535D02*
X791339D01*
G01D02*
G03X787402Y1654331I0J-3937D01*
G01X779528D02*
G03X775591Y1658268I-3937J0D01*
G01X779528Y1654331D02*
Y1626772D01*
G01D02*
G03X787402I3937J0D01*
G01X779528Y1654331D02*
Y1626772D01*
G01D02*
G03X787402I3937J0D01*
G01X806437Y277843D02*
G03X813362Y264712I37662J11471D01*
G01X806437Y277843D02*
G03X813362Y264712I37662J11471D01*
G01X806437Y750284D02*
G03X813362Y737153I37662J11471D01*
G01X806437Y750284D02*
G03X813362Y737154I37661J11472D01*
G01X866142Y-148819D02*
Y-11811D01*
G01Y-148819D02*
G03X870079Y-152756I3937J0D01*
G01X866142Y-11811D02*
Y-148819D01*
G01D02*
G03X870079Y-152756I3937J0D01*
G01X866142Y-129134D02*
G03X858268I-3937J0D01*
G01X866142D02*
G03X858268I-3937J0D01*
G01Y-148819D02*
Y-129134D01*
G01X854331Y-152756D02*
G03X858268Y-148819I0J3937D01*
G01D02*
Y-129134D01*
G01X854331Y-152756D02*
G03X858268Y-148819I0J3937D01*
G01X1177165Y-152756D02*
X870079D01*
G01D02*
X1177165D01*
G01X858268Y-98425D02*
Y-15748D01*
G01Y-98425D02*
Y-15748D01*
G01Y-98425D02*
G03X866142I3937J0D01*
G01X858268D02*
G03X866142I3937J0D01*
G01Y-11811D02*
G03X862205Y-7874I-3937J0D01*
G01X866142Y-11811D02*
G03X862205Y-7874I-3937J0D01*
G01X927032Y-57820D02*
G03X962731I17850J-12259D01*
G01X927032Y-57821D02*
G03X962732I17850J-12258D01*
G01X927032Y-57820D02*
G03X935199Y-42571I-64908J44575D01*
G01X954565D02*
G03X935199I-9683J-3885D01*
G01X927032Y-57821D02*
G03X935199Y-42571I-64909J44573D01*
G01X954564D02*
G03X935199I-9682J-3885D01*
G01X944512Y1089122D02*
G03X978323I16905J-13531D01*
G01X944512Y1089121D02*
G03X978323I16905J-13531D01*
G01X944512Y1431641D02*
G03X978323I16905J-13531D01*
G01X944512D02*
G03X978323I16905J-13531D01*
G01X954565Y-42571D02*
G03X962731Y-57820I73077J29322D01*
G01X954564Y-42570D02*
G03X962732Y-57821I73076J29324D01*
G01X971398Y1102252D02*
G03X978323Y1089122I37661J11472D01*
G01X971398Y1102252D02*
G03X978323Y1089121I37662J11471D01*
G01X971398Y1102252D02*
G03X951437I-9980J-3039D01*
G01X971398D02*
G03X951437I-9980J-3039D01*
G01X944512Y1089122D02*
G03X951437Y1102252I-30737J24602D01*
G01X944512Y1089121D02*
G03X951437Y1102252I-30737J24602D01*
G01X971398Y1444772D02*
G03X978323Y1431641I37662J11471D01*
G01X971398Y1444772D02*
G03X978323Y1431641I37662J11471D01*
G01X971398Y1444772D02*
G03X951437I-9980J-3040D01*
G01X944512Y1431641D02*
G03X951437Y1444772I-30737J24602D01*
G01X944512Y1431641D02*
G03X951437Y1444772I-30737J24602D01*
G01X971398D02*
G03X951437I-9980J-3039D01*
G01X1181102Y-148819D02*
Y-3937D01*
G01X1177165Y-152756D02*
G03X1181102Y-148819I0J3937D01*
G01X1177165Y-152756D02*
G03X1181102Y-148819I0J3937D01*
G01D02*
Y-3937D01*
G01Y-94488D02*
G03X1188976I3937J0D01*
G01X1181102D02*
G03X1188976I3937J0D01*
G01Y-125197D02*
G03X1181102I-3937J0D01*
G01X1188976D02*
G03X1181102I-3937J0D01*
G01X1185039Y0D02*
G03X1181102Y-3937I0J-3937D01*
G01X1185039Y0D02*
G03X1181102Y-3937I0J-3937D01*
G01X1164984Y557626D02*
G03X1198795I16906J-13531D01*
G01X1164984Y557625D02*
G03X1198795I16906J-13531D01*
G01X1191870Y570756D02*
G03X1171909I-9980J-3039D01*
G01X1191870D02*
G03X1171909I-9980J-3039D01*
G01X1164984Y557626D02*
G03X1171909Y570756I-30736J24602D01*
G01X1164984Y557625D02*
G03X1171909Y570756I-30737J24602D01*
G01X1164984Y971011D02*
G03X1198795I16906J-13531D01*
G01X1164984D02*
G03X1198795I16906J-13531D01*
G01X1191870Y984142D02*
G03X1171909I-9980J-3040D01*
G01X1191870D02*
G03X1171909I-9980J-3039D01*
G01X1164984Y971011D02*
G03X1171909Y984142I-30737J24602D01*
G01X1164984Y971011D02*
G03X1171909Y984142I-30737J24602D01*
G01X1164173Y1378740D02*
Y1468504D01*
G01X1930906Y1374803D02*
X1168110D01*
G01X1164173Y1378740D02*
G03X1168110Y1374803I3937J0D01*
G01X1172047Y1382677D02*
Y1464567D01*
G01X1195669Y1382677D02*
X1172047D01*
G01X1930906Y1374803D02*
X1168110D01*
G01X1164173Y1378740D02*
G03X1168110Y1374804I3937J1D01*
G01X1164173Y1378740D02*
Y1468504D01*
G01X1172047Y1382677D02*
Y1464567D01*
G01X1195669Y1382677D02*
X1172047D01*
G01X1168110Y1472441D02*
G03X1164173Y1468504I0J-3937D01*
G01X1168110Y1472441D02*
G03X1164173Y1468504I0J-3937D01*
G01X1172047Y1464567D02*
X1216535D01*
G01X1172047D02*
X1216535D01*
G01X1168110Y1472441D02*
X1216535D01*
G01X1168110D02*
X1216535D01*
G01X1164984Y1561563D02*
G03X1171909Y1574693I-30736J24602D01*
G01X1164984Y1561562D02*
G03X1171909Y1574693I-30737J24602D01*
G01X1164984Y1561563D02*
G03X1198795I16906J-13531D01*
G01X1164984Y1561562D02*
G03X1198795I16906J-13531D01*
G01X1191870Y1574693D02*
G03X1171909I-9980J-3039D01*
G01X1191870D02*
G03X1171909I-9980J-3039D01*
G01X1188976Y-148819D02*
Y-125197D01*
G01Y-148819D02*
G03X1192913Y-152756I3937J0D01*
G01X1188976Y-148819D02*
Y-125197D01*
G01Y-148819D02*
G03X1192913Y-152756I3937J0D01*
G01D02*
X1919843D01*
G01X1192913D02*
X1919843D01*
G01X1188976Y-94488D02*
Y-7874D01*
G01Y-94488D02*
Y-7874D01*
G01X1185039Y0D02*
X1366142D01*
G01X1188976Y-7874D02*
X1315748D01*
G01X1185039Y0D02*
X1366142D01*
G01X1188976Y-7874D02*
X1315748D01*
G01X1191870Y570756D02*
G03X1198795Y557626I37662J11472D01*
G01X1191870Y570756D02*
G03X1198795Y557626I37662J11472D01*
G01X1191870Y984142D02*
G03X1198795Y971011I37662J11471D01*
G01X1191870Y984142D02*
G03X1198795Y971011I37662J11471D01*
G01X1524606Y1382677D02*
X1226378D01*
G01X1524606D02*
X1226378D01*
G01X1195669Y1374803D02*
G03Y1382677I0J3937D01*
G01X1226378D02*
G03Y1374803I0J-3937D01*
G01X1195669D02*
G03Y1382677I0J3937D01*
G01X1226378D02*
G03Y1374803I0J-3937D01*
G01X1216535Y1464567D02*
G03X1228346Y1476378I0J11811D01*
G01X1216535Y1464567D02*
G03X1228346Y1476378I0J11811D01*
G01Y1592126D02*
Y1476378D01*
G01Y1592126D02*
Y1476378D01*
G01X1220472Y1654331D02*
Y1476378D01*
G01X1216535Y1472441D02*
G03X1220472Y1476378I0J3937D01*
G01X1216535Y1472441D02*
G03X1220472Y1476378I0J3937D01*
G01D02*
Y1654331D01*
G01X1191870Y1574693D02*
G03X1198795Y1561563I37662J11472D01*
G01X1191870Y1574693D02*
G03X1198795Y1561562I37662J11471D01*
G01X1228346Y1592126D02*
G03X1220472I-3937J0D01*
G01X1228346D02*
G03X1220472I-3937J0D01*
G01X1232283Y1658268D02*
X1442382D01*
G01X1232283D02*
G03X1228346Y1654331I0J-3937D01*
G01X1232283Y1658268D02*
X1442382D01*
G01X1232283D02*
G03X1228346Y1654331I0J-3937D01*
G01D02*
Y1622835D01*
G01Y1654331D02*
Y1622835D01*
G01X1220472Y1654331D02*
G03X1216535Y1658268I-3937J0D01*
G01X1220472Y1654331D02*
G03X1216535Y1658268I-3937J0D01*
G01X1220472Y1622835D02*
G03X1228346I3937J0D01*
G01X1220472D02*
G03X1228346I3937J0D01*
G01X1284965Y378885D02*
G03X1318776I16906J-13531D01*
G01X1284965D02*
G03X1318775I16905J-13531D01*
G01X1284965Y831641D02*
G03X1318776I16906J-13531D01*
G01X1284965D02*
G03X1318775I16905J-13531D01*
G01X1284965Y1284397D02*
G03X1318776I16906J-13531D01*
G01X1284965D02*
G03X1318775I16905J-13531D01*
G01X1315748Y-7874D02*
G03Y0I0J3937D01*
G01Y-7874D02*
G03Y0I0J3937D01*
G01X1311850Y392016D02*
G03X1291890I-9980J-3040D01*
G01X1311850D02*
G03X1318776Y378885I37662J11473D01*
G01X1311851Y392016D02*
G03X1291890I-9980J-3039D01*
G01X1311851D02*
G03X1318775Y378885I37663J11469D01*
G01X1284965D02*
G03X1291890Y392016I-30737J24602D01*
G01X1284965Y378885D02*
G03X1291890Y392016I-30737J24602D01*
G01X1284965Y831641D02*
G03X1291890Y844772I-30737J24602D01*
G01X1311850D02*
G03X1318776Y831641I37662J11473D01*
G01X1284965D02*
G03X1291890Y844772I-30737J24602D01*
G01X1311851D02*
G03X1318775Y831641I37663J11469D01*
G01X1311850Y844772D02*
G03X1291890I-9980J-3040D01*
G01X1311851D02*
G03X1291890I-9980J-3039D01*
G01X1284965Y1284397D02*
G03X1291890Y1297528I-30737J24602D01*
G01X1311850D02*
G03X1291890I-9980J-3040D01*
G01X1311850D02*
G03X1318776Y1284397I37661J11473D01*
G01X1284965D02*
G03X1291890Y1297528I-30737J24602D01*
G01X1311851D02*
G03X1291890I-9980J-3040D01*
G01X1311851D02*
G03X1318775Y1284397I37663J11469D01*
G01X1377953Y3937D02*
Y51181D01*
G01Y3937D02*
Y51181D01*
G01X1370079Y3937D02*
Y55118D01*
G01X1366142Y0D02*
G03X1370079Y3937I0J3937D01*
G01X1366142Y-7874D02*
G03X1377953Y3937I0J11811D01*
G01X1346457Y-7874D02*
X1366142D01*
G01Y0D02*
G03X1370079Y3937I0J3937D01*
G01D02*
Y55118D01*
G01X1346457Y-7874D02*
X1366142D01*
G01D02*
G03X1377953Y3937I0J11811D01*
G01X1346457Y0D02*
G03Y-7874I0J-3937D01*
G01Y0D02*
G03Y-7874I0J-3937D01*
G01X1374016Y59055D02*
G03X1370079Y55118I0J-3937D01*
G01X1374016Y59056D02*
G03X1370079Y55118I0J-3937D01*
G01X1374016Y59055D02*
X1555118D01*
G01X1377953Y51181D02*
X1551181D01*
G01X1374016Y59055D02*
X1555118D01*
G01X1377953Y51181D02*
X1551181D01*
G01X1442382Y1658268D02*
G03X1450256I3937J0D01*
G01X1442382D02*
G03X1450256I3937J0D01*
G01D02*
X1919843D01*
G01X1450256D02*
X1919843D01*
G01X1562992Y0D02*
X1930906D01*
G01X1559055Y55118D02*
Y3937D01*
G01D02*
G03X1562992Y0I3937J0D01*
G01Y-7874D02*
X1593701D01*
G01X1559055Y55118D02*
Y3937D01*
G01D02*
G03X1562992Y0I3937J0D01*
G01D02*
X1930906D01*
G01X1562992Y-7874D02*
X1593701D01*
G01X1551181Y51181D02*
Y3937D01*
G01D02*
G03X1562992Y-7874I11811J0D01*
G01X1551181Y51181D02*
Y3937D01*
G01D02*
G03X1562992Y-7874I11811J0D01*
G01X1559055Y55118D02*
G03X1555118Y59055I-3937J0D01*
G01X1559055Y55118D02*
G03X1555118Y59055I-3937J0D01*
G01X1532996Y378885D02*
G03X1566807I16906J-13531D01*
G01X1532996D02*
G03X1566807I16906J-13531D01*
G01X1559882Y392016D02*
G03X1566807Y378885I37662J11471D01*
G01X1559882Y392016D02*
G03X1566807Y378885I37662J11471D01*
G01X1559882Y392016D02*
G03X1539921I-9980J-3039D01*
G01X1559882D02*
G03X1539921I-9980J-3039D01*
G01X1532996Y378885D02*
G03X1539921Y392016I-30737J24602D01*
G01X1532996Y378885D02*
G03X1539921Y392016I-30737J24602D01*
G01X1559882Y844772D02*
G03X1566807Y831641I37662J11471D01*
G01X1559882Y844772D02*
G03X1566807Y831641I37662J11471D01*
G01X1532996D02*
G03X1539921Y844772I-30737J24602D01*
G01X1532996Y831641D02*
G03X1539921Y844772I-30737J24602D01*
G01X1532996Y831641D02*
G03X1566807I16906J-13531D01*
G01X1532996D02*
G03X1566807I16906J-13531D01*
G01X1559882Y844772D02*
G03X1539921I-9980J-3040D01*
G01X1559882D02*
G03X1539921I-9980J-3039D01*
G01X1532996Y1284397D02*
G03X1566807I16906J-13531D01*
G01X1532996D02*
G03X1566807I16906J-13531D01*
G01X1559882Y1297528D02*
G03X1566807Y1284397I37662J11471D01*
G01X1559882Y1297528D02*
G03X1566807Y1284397I37662J11471D01*
G01X1559882Y1297528D02*
G03X1539921I-9980J-3040D01*
G01X1532996Y1284397D02*
G03X1539921Y1297528I-30737J24602D01*
G01X1532996Y1284397D02*
G03X1539921Y1297528I-30737J24602D01*
G01X1559882D02*
G03X1539921I-9980J-3040D01*
G01X1563976Y1382677D02*
G03Y1374803I0J-3937D01*
G01Y1382677D02*
G03Y1374803I0J-3937D01*
G01X1524606D02*
G03Y1382677I0J3937D01*
G01Y1374803D02*
G03Y1382677I0J3937D01*
G01X1864567D02*
X1563976D01*
G01X1864567D02*
X1563976D01*
G01X1593701Y-7874D02*
G03Y0I0J3937D01*
G01Y-7874D02*
G03Y0I0J3937D01*
G01X1633071D02*
G03Y-7874I0J-3937D01*
G01D02*
X1880512D01*
G01X1633071D02*
X1880512D01*
G01X1633071Y0D02*
G03Y-7874I0J-3937D01*
G01X1693996Y829921D02*
G03X1653839I-20078J0D01*
G01X1693996D02*
G03I-20079J0D01*
G01X1653839D02*
G03X1693996I20078J0D01*
G01X1781028Y378885D02*
G03X1814839I16906J-13531D01*
G01X1781028D02*
G03X1814838I16905J-13531D01*
G01X1807913Y392016D02*
G03X1814839Y378885I37662J11473D01*
G01X1807914Y392016D02*
G03X1814838Y378885I37663J11469D01*
G01X1807913Y392016D02*
G03X1787953I-9980J-3040D01*
G01X1807914D02*
G03X1787953I-9980J-3039D01*
G01X1781028Y378885D02*
G03X1787953Y392016I-30737J24602D01*
G01X1781028Y378885D02*
G03X1787953Y392016I-30737J24602D01*
G01X1807913Y844772D02*
G03X1814839Y831641I37662J11473D01*
G01X1807914Y844772D02*
G03X1814838Y831641I37663J11469D01*
G01X1781028D02*
G03X1787953Y844772I-30737J24602D01*
G01X1781028Y831641D02*
G03X1787953Y844772I-30737J24602D01*
G01X1781028Y831641D02*
G03X1814839I16906J-13531D01*
G01X1781028D02*
G03X1814838I16905J-13531D01*
G01X1807913Y844772D02*
G03X1787953I-9980J-3040D01*
G01X1807914D02*
G03X1787953I-9980J-3039D01*
G01X1781028Y1284397D02*
G03X1814839I16906J-13531D01*
G01X1781028D02*
G03X1814838I16905J-13531D01*
G01X1807913Y1297528D02*
G03X1814839Y1284397I37661J11473D01*
G01X1807914Y1297528D02*
G03X1814838Y1284397I37663J11469D01*
G01X1807913Y1297528D02*
G03X1787953I-9980J-3040D01*
G01X1781028Y1284397D02*
G03X1787953Y1297528I-30737J24602D01*
G01X1781028Y1284397D02*
G03X1787953Y1297528I-30737J24602D01*
G01X1807914D02*
G03X1787953I-9980J-3040D01*
G01X1911220Y0D02*
G03Y-7874I0J-3937D01*
G01Y0D02*
G03Y-7874I0J-3937D01*
G01X1880512D02*
G03Y0I0J3937D01*
G01Y-7874D02*
G03Y0I0J3937D01*
G01X1930906Y1382677D02*
X1895276D01*
G01D02*
G03Y1374803I0J-3937D01*
G01X1930906Y1382677D02*
X1895276D01*
G01D02*
G03Y1374803I0J-3937D01*
G01X1864567D02*
G03Y1382677I0J3937D01*
G01Y1374803D02*
G03Y1382677I0J3937D01*
G01X1919843Y-152756D02*
G03X1934843Y-137756I0J15000D01*
G01X1919843Y-152756D02*
G03X1934843Y-137756I0J15000D01*
G01Y-11811D02*
Y-137756D01*
G01Y-11811D02*
Y-137756D01*
G01X1930906Y0D02*
G03X1934843Y3937I0J3937D01*
G01X1930906Y0D02*
G03X1934843Y3937I0J3937D01*
G01Y-11811D02*
G03X1930906Y-7874I-3937J0D01*
G01X1934843Y-11811D02*
G03X1930906Y-7874I-3937J0D01*
G01X1911220D02*
X1930906D01*
G01X1911220D02*
X1930906D01*
G01X1934843Y1370866D02*
Y3937D01*
G01D02*
Y1370866D01*
G01D02*
G03X1930906Y1374803I-3937J0D01*
G01X1934843Y1370866D02*
G03X1930906Y1374803I-3937J0D01*
G01Y1382677D02*
G03X1934843Y1386614I0J3937D01*
G01X1930906Y1382677D02*
G03X1934843Y1386614I0J3937D01*
G01D02*
Y1643268D01*
G01Y1386614D02*
Y1643268D01*
G01D02*
G03X1919843Y1658268I-15000J0D01*
G01X1934843Y1643268D02*
G03X1919843Y1658268I-15000J0D01*
G54D12*
G01X433842Y72402D02*
Y139772D01*
G01X432692Y72402D02*
Y139952D01*
G01X433360Y71236D02*
G03X433842Y72402I-1168J1165D01*
G01X432546Y72049D02*
G03X432692Y72402I-354J353D01*
G01X433096Y70971D02*
X433360Y71236D01*
G01X432282Y71785D02*
X432546Y72049D01*
G01X431929Y70489D02*
G03X433096Y70971I1J1650D01*
G01X431929Y71639D02*
G03X432282Y71785I0J500D01*
G01X430286Y70489D02*
X431929D01*
G01X430285Y71639D02*
X431929D01*
G01X432692Y72402D02*
Y139952D01*
G01X433842Y72402D02*
Y139772D01*
G01X432546Y72049D02*
G03X432692Y72402I-354J353D01*
G01X433360Y71236D02*
G03X433842Y72402I-1168J1165D01*
G01X432282Y71785D02*
X432546Y72049D01*
G01X433096Y70971D02*
X433360Y71236D01*
G01X431929Y71639D02*
G03X432282Y71785I0J500D01*
G01X431929Y70489D02*
G03X433096Y70971I1J1650D01*
G01X430285Y71639D02*
X431929D01*
G01X430286Y70489D02*
X431929D01*
G01X440929Y76339D02*
Y125946D01*
G01X439779Y76339D02*
Y126291D01*
G01X440447Y75173D02*
G03X440929Y76339I-1168J1165D01*
G01X439633Y75986D02*
G03X439779Y76339I-354J353D01*
G01X440183Y74908D02*
X440447Y75173D01*
G01X439369Y75722D02*
X439633Y75986D01*
G01X439016Y74426D02*
G03X440183Y74908I1J1650D01*
G01X439016Y75576D02*
G03X439369Y75722I0J500D01*
G01X437373Y74426D02*
X439016D01*
G01X437372Y75576D02*
X439016D01*
G01X439779Y76339D02*
Y126291D01*
G01X440929Y76339D02*
Y125946D01*
G01X439633Y75986D02*
G03X439779Y76339I-354J353D01*
G01X440447Y75173D02*
G03X440929Y76339I-1168J1165D01*
G01X439369Y75722D02*
X439633Y75986D01*
G01X440183Y74908D02*
X440447Y75173D01*
G01X439016Y75576D02*
G03X439369Y75722I0J500D01*
G01X439016Y74426D02*
G03X440183Y74908I1J1650D01*
G01X437372Y75576D02*
X439016D01*
G01X437373Y74426D02*
X439016D01*
G01X448016Y72402D02*
Y125342D01*
G01X446866Y72402D02*
Y125687D01*
G01X447534Y71236D02*
G03X448016Y72402I-1168J1165D01*
G01X446720Y72049D02*
G03X446866Y72402I-354J353D01*
G01X447270Y70971D02*
X447534Y71236D01*
G01X446456Y71785D02*
X446720Y72049D01*
G01X446103Y70489D02*
G03X447270Y70971I1J1650D01*
G01X446103Y71639D02*
G03X446456Y71785I0J500D01*
G01X444460Y70489D02*
X446103D01*
G01X444459Y71639D02*
X446103D01*
G01X446866Y72402D02*
Y125687D01*
G01X448016Y72402D02*
Y125342D01*
G01X446720Y72049D02*
G03X446866Y72402I-354J353D01*
G01X447534Y71236D02*
G03X448016Y72402I-1168J1165D01*
G01X446456Y71785D02*
X446720Y72049D01*
G01X447270Y70971D02*
X447534Y71236D01*
G01X446103Y71639D02*
G03X446456Y71785I0J500D01*
G01X446103Y70489D02*
G03X447270Y70971I1J1650D01*
G01X444459Y71639D02*
X446103D01*
G01X444460Y70489D02*
X446103D01*
G01X455102Y76339D02*
Y128382D01*
G01X453952Y76339D02*
Y128727D01*
G01X454620Y75173D02*
G03X455102Y76339I-1168J1165D01*
G01X453806Y75986D02*
G03X453952Y76339I-354J353D01*
G01X454356Y74908D02*
X454620Y75173D01*
G01X453542Y75722D02*
X453806Y75986D01*
G01X453189Y74426D02*
G03X454356Y74908I1J1650D01*
G01X453189Y75576D02*
G03X453542Y75722I0J500D01*
G01X451546Y74426D02*
X453189D01*
G01X451545Y75576D02*
X453189D01*
G01X453952Y76339D02*
Y128727D01*
G01X455102Y76339D02*
Y128382D01*
G01X453806Y75986D02*
G03X453952Y76339I-354J353D01*
G01X454620Y75173D02*
G03X455102Y76339I-1168J1165D01*
G01X453542Y75722D02*
X453806Y75986D01*
G01X454356Y74908D02*
X454620Y75173D01*
G01X453189Y75576D02*
G03X453542Y75722I0J500D01*
G01X453189Y74426D02*
G03X454356Y74908I1J1650D01*
G01X451545Y75576D02*
X453189D01*
G01X451546Y74426D02*
X453189D01*
G01X458633Y70489D02*
X460276D01*
G01X458632Y71639D02*
X460276D01*
G01X458632D02*
X460276D01*
G01X458633Y70489D02*
X460276D01*
G01X433842Y139772D02*
X472694Y198777D01*
G01X432783Y140255D02*
X471799Y199510D01*
G01X432783Y140255D02*
X471799Y199510D01*
G01X433842Y139772D02*
X472694Y198777D01*
G01X440929Y125946D02*
X494634Y207504D01*
G01X439779Y126291D02*
X493800Y208329D01*
G01X439779Y126291D02*
X493800Y208329D01*
G01X440929Y125946D02*
X494634Y207504D01*
G01X448016Y125342D02*
X500995Y205808D01*
G01X446866Y125687D02*
X500161Y206633D01*
G01X446866Y125687D02*
X500161Y206633D01*
G01X448016Y125342D02*
X500995Y205808D01*
G01X455102Y128382D02*
X499300Y195536D01*
G01X453952Y128727D02*
X498469Y196366D01*
G01X453952Y128727D02*
X498469Y196366D01*
G01X455102Y128382D02*
X499300Y195536D01*
G01X469275Y76339D02*
Y120347D01*
G01X468125Y76339D02*
Y120692D01*
G01X468793Y75173D02*
G03X469275Y76339I-1168J1165D01*
G01X467979Y75986D02*
G03X468125Y76339I-354J353D01*
G01X468529Y74908D02*
X468793Y75173D01*
G01X467715Y75722D02*
X467979Y75986D01*
G01X467362Y74426D02*
G03X468529Y74908I1J1650D01*
G01X467362Y75576D02*
G03X467715Y75722I0J500D01*
G01X465719Y74426D02*
X467362D01*
G01X465718Y75576D02*
X467362D01*
G01X468125Y76339D02*
Y120692D01*
G01X469275Y76339D02*
Y120347D01*
G01X467979Y75986D02*
G03X468125Y76339I-354J353D01*
G01X468793Y75173D02*
G03X469275Y76339I-1168J1165D01*
G01X467715Y75722D02*
X467979Y75986D01*
G01X468529Y74908D02*
X468793Y75173D01*
G01X467362Y75576D02*
G03X467715Y75722I0J500D01*
G01X467362Y74426D02*
G03X468529Y74908I1J1650D01*
G01X465718Y75576D02*
X467362D01*
G01X465719Y74426D02*
X467362D01*
G01X476362Y72402D02*
Y123472D01*
G01X475212Y72402D02*
Y123817D01*
G01X475880Y71236D02*
G03X476362Y72402I-1168J1165D01*
G01X475066Y72049D02*
G03X475212Y72402I-354J353D01*
G01X475616Y70971D02*
X475880Y71236D01*
G01X474802Y71785D02*
X475066Y72049D01*
G01X474449Y70489D02*
G03X475616Y70971I1J1650D01*
G01X474449Y71639D02*
G03X474802Y71785I0J500D01*
G01X472806Y70489D02*
X474449D01*
G01X472805Y71639D02*
X474449D01*
G01X475212Y72402D02*
Y123817D01*
G01X476362Y72402D02*
Y123472D01*
G01X475066Y72049D02*
G03X475212Y72402I-354J353D01*
G01X475880Y71236D02*
G03X476362Y72402I-1168J1165D01*
G01X474802Y71785D02*
X475066Y72049D01*
G01X475616Y70971D02*
X475880Y71236D01*
G01X474449Y71639D02*
G03X474802Y71785I0J500D01*
G01X474449Y70489D02*
G03X475616Y70971I1J1650D01*
G01X472805Y71639D02*
X474449D01*
G01X472806Y70489D02*
X474449D01*
G01X483449Y76339D02*
Y117657D01*
G01X482299Y76339D02*
Y117776D01*
G01X482967Y75173D02*
G03X483449Y76339I-1168J1165D01*
G01X482153Y75986D02*
G03X482299Y76339I-354J353D01*
G01X482703Y74908D02*
X482967Y75173D01*
G01X481889Y75722D02*
X482153Y75986D01*
G01X481536Y74426D02*
G03X482703Y74908I1J1650D01*
G01X481536Y75576D02*
G03X481889Y75722I0J500D01*
G01X479893Y74426D02*
X481536D01*
G01X479892Y75576D02*
X481536D01*
G01X482299Y76339D02*
Y117776D01*
G01X483449Y76339D02*
Y117657D01*
G01X482153Y75986D02*
G03X482299Y76339I-354J353D01*
G01X482967Y75173D02*
G03X483449Y76339I-1168J1165D01*
G01X481889Y75722D02*
X482153Y75986D01*
G01X482703Y74908D02*
X482967Y75173D01*
G01X481536Y75576D02*
G03X481889Y75722I0J500D01*
G01X481536Y74426D02*
G03X482703Y74908I1J1650D01*
G01X479892Y75576D02*
X481536D01*
G01X479893Y74426D02*
X481536D01*
G01X462189Y72402D02*
Y130638D01*
G01X461039Y72402D02*
Y130983D01*
G01X461707Y71236D02*
G03X462189Y72402I-1168J1165D01*
G01X460893Y72049D02*
G03X461039Y72402I-354J353D01*
G01X461443Y70971D02*
X461707Y71236D01*
G01X460629Y71785D02*
X460893Y72049D01*
G01X460276Y70489D02*
G03X461443Y70971I1J1650D01*
G01X460276Y71639D02*
G03X460629Y71785I0J500D01*
G01X461039Y72402D02*
Y130983D01*
G01X462189Y72402D02*
Y130638D01*
G01X460893Y72049D02*
G03X461039Y72402I-354J353D01*
G01X461707Y71236D02*
G03X462189Y72402I-1168J1165D01*
G01X460629Y71785D02*
X460893Y72049D01*
G01X461443Y70971D02*
X461707Y71236D01*
G01X460276Y71639D02*
G03X460629Y71785I0J500D01*
G01X460276Y70489D02*
G03X461443Y70971I1J1650D01*
G01X469275Y120347D02*
X498820Y165219D01*
G01X468125Y120692D02*
X497986Y166044D01*
G01X468125Y120692D02*
X497986Y166044D01*
G01X469275Y120347D02*
X498820Y165219D01*
G01X484965Y138627D02*
X604896Y200410D01*
G01X485760Y137742D02*
X590230Y191561D01*
G01X484965Y138627D02*
X604896Y200410D01*
G01X476362Y123472D02*
X485760Y137742D01*
G01X475212Y123817D02*
X484965Y138627D01*
G01D02*
X604896Y200410D01*
G01X485760Y137742D02*
X590230Y191561D01*
G01X475212Y123817D02*
X484965Y138627D01*
G01X476362Y123472D02*
X485760Y137742D01*
G01X491856Y131472D02*
X614510Y194660D01*
G01X491062Y132358D02*
X614125Y195756D01*
G01X483777Y119265D02*
X491856Y131472D01*
G01X482694Y119714D02*
X491062Y132358D01*
G01X483449Y117657D02*
X483777Y119265D01*
G01X482299Y117776D02*
X482694Y119714D01*
G01X491062Y132358D02*
X614125Y195756D01*
G01X491856Y131472D02*
X614510Y194660D01*
G01X482694Y119714D02*
X491062Y132358D01*
G01X483777Y119265D02*
X491856Y131472D01*
G01X482299Y117776D02*
X482694Y119714D01*
G01X483449Y117657D02*
X483777Y119265D01*
G01X480992Y159186D02*
X568948Y217400D01*
G01X480160Y160016D02*
X513737Y182238D01*
G01X462189Y130638D02*
X480992Y159186D01*
G01X461039Y130983D02*
X480160Y160016D01*
G01X480992Y159186D02*
X568948Y217400D01*
G01X480992Y159186D02*
X568948Y217400D01*
G01X480992Y159186D02*
X568948Y217400D01*
G01X480160Y160016D02*
X513737Y182238D01*
G01X480992Y159186D02*
X568948Y217400D01*
G01X461039Y130983D02*
X480160Y160016D01*
G01X462189Y130638D02*
X480992Y159186D01*
G01X498820Y165219D02*
X553863Y202357D01*
G01X497986Y166044D02*
X525698Y184742D01*
G01X498820Y165219D02*
X553863Y202357D01*
G01X497986Y166044D02*
X525698Y184742D01*
G01X498820Y165219D02*
X553863Y202357D01*
G01X472694Y198777D02*
X618821Y297339D01*
G01X471951Y199664D02*
X618370Y298422D01*
G01X471951Y199664D02*
X618370Y298422D01*
G01X472694Y198777D02*
X618821Y297339D01*
G01X494634Y207504D02*
X619397Y291661D01*
G01X493800Y208329D02*
X618946Y292744D01*
G01X493800Y208329D02*
X618946Y292744D01*
G01X494634Y207504D02*
X619397Y291661D01*
G01X500995Y205808D02*
X620512Y286425D01*
G01X500161Y206633D02*
X560109Y247070D01*
G01X500995Y205808D02*
X620512Y286425D01*
G01X500161Y206633D02*
X560109Y247070D01*
G01X500995Y205808D02*
X620512Y286425D01*
G01X499300Y195536D02*
X612039Y269946D01*
G01X498469Y196366D02*
X611593Y271031D01*
G01X498469Y196366D02*
X611593Y271031D01*
G01X499300Y195536D02*
X612039Y269946D01*
G01X518882Y72402D02*
Y124473D01*
G01X517732Y72402D02*
Y124818D01*
G01X518400Y71236D02*
G03X518882Y72402I-1168J1165D01*
G01X517586Y72049D02*
G03X517732Y72402I-354J353D01*
G01X518136Y70971D02*
X518400Y71236D01*
G01X517322Y71785D02*
X517586Y72049D01*
G01X516969Y70489D02*
G03X518136Y70971I1J1650D01*
G01X516969Y71639D02*
G03X517322Y71785I0J500D01*
G01X515326Y70489D02*
X516969D01*
G01X515325Y71639D02*
X516969D01*
G01X517732Y72402D02*
Y124818D01*
G01X518882Y72402D02*
Y124473D01*
G01X517586Y72049D02*
G03X517732Y72402I-354J353D01*
G01X518400Y71236D02*
G03X518882Y72402I-1168J1165D01*
G01X517322Y71785D02*
X517586Y72049D01*
G01X518136Y70971D02*
X518400Y71236D01*
G01X516969Y71639D02*
G03X517322Y71785I0J500D01*
G01X516969Y70489D02*
G03X518136Y70971I1J1650D01*
G01X515325Y71639D02*
X516969D01*
G01X515326Y70489D02*
X516969D01*
G01X525968Y76339D02*
Y122015D01*
G01X524818Y76339D02*
Y122360D01*
G01X525486Y75173D02*
G03X525968Y76339I-1168J1165D01*
G01X524672Y75986D02*
G03X524818Y76339I-354J353D01*
G01X525222Y74908D02*
X525486Y75173D01*
G01X524408Y75722D02*
X524672Y75986D01*
G01X524055Y74426D02*
G03X525222Y74908I1J1650D01*
G01X524055Y75576D02*
G03X524408Y75722I0J500D01*
G01X522412Y74426D02*
X524055D01*
G01X522411Y75576D02*
X524055D01*
G01X524818Y76339D02*
Y122360D01*
G01X525968Y76339D02*
Y122015D01*
G01X524672Y75986D02*
G03X524818Y76339I-354J353D01*
G01X525486Y75173D02*
G03X525968Y76339I-1168J1165D01*
G01X524408Y75722D02*
X524672Y75986D01*
G01X525222Y74908D02*
X525486Y75173D01*
G01X524055Y75576D02*
G03X524408Y75722I0J500D01*
G01X524055Y74426D02*
G03X525222Y74908I1J1650D01*
G01X522411Y75576D02*
X524055D01*
G01X522412Y74426D02*
X524055D01*
G01X533055Y72402D02*
Y124336D01*
G01X531905Y72402D02*
Y124681D01*
G01X532573Y71236D02*
G03X533055Y72402I-1168J1165D01*
G01X531759Y72049D02*
G03X531905Y72402I-354J353D01*
G01X532309Y70971D02*
X532573Y71236D01*
G01X531495Y71785D02*
X531759Y72049D01*
G01X531142Y70489D02*
G03X532309Y70971I1J1650D01*
G01X531142Y71639D02*
G03X531495Y71785I0J500D01*
G01X529499Y70489D02*
X531142D01*
G01X529498Y71639D02*
X531142D01*
G01X531905Y72402D02*
Y124681D01*
G01X533055Y72402D02*
Y124336D01*
G01X531759Y72049D02*
G03X531905Y72402I-354J353D01*
G01X532573Y71236D02*
G03X533055Y72402I-1168J1165D01*
G01X531495Y71785D02*
X531759Y72049D01*
G01X532309Y70971D02*
X532573Y71236D01*
G01X531142Y71639D02*
G03X531495Y71785I0J500D01*
G01X531142Y70489D02*
G03X532309Y70971I1J1650D01*
G01X529498Y71639D02*
X531142D01*
G01X529499Y70489D02*
X531142D01*
G01X540142Y76339D02*
Y123734D01*
G01X538992Y76339D02*
Y124079D01*
G01X539660Y75173D02*
G03X540142Y76339I-1168J1165D01*
G01X538846Y75986D02*
G03X538992Y76339I-354J353D01*
G01X539396Y74908D02*
X539660Y75173D01*
G01X538582Y75722D02*
X538846Y75986D01*
G01X538229Y74426D02*
G03X539396Y74908I1J1650D01*
G01X538229Y75576D02*
G03X538582Y75722I0J500D01*
G01X536586Y74426D02*
X538229D01*
G01X536585Y75576D02*
X538229D01*
G01X538992Y76339D02*
Y124079D01*
G01X540142Y76339D02*
Y123734D01*
G01X538846Y75986D02*
G03X538992Y76339I-354J353D01*
G01X539660Y75173D02*
G03X540142Y76339I-1168J1165D01*
G01X538582Y75722D02*
X538846Y75986D01*
G01X539396Y74908D02*
X539660Y75173D01*
G01X538229Y75576D02*
G03X538582Y75722I0J500D01*
G01X538229Y74426D02*
G03X539396Y74908I1J1650D01*
G01X536585Y75576D02*
X538229D01*
G01X536586Y74426D02*
X538229D01*
G01X547228Y72402D02*
Y125413D01*
G01X546078Y72402D02*
Y125758D01*
G01X546746Y71236D02*
G03X547228Y72402I-1168J1165D01*
G01X545932Y72049D02*
G03X546078Y72402I-354J353D01*
G01X546482Y70971D02*
X546746Y71236D01*
G01X545668Y71785D02*
X545932Y72049D01*
G01X545315Y70489D02*
G03X546482Y70971I1J1650D01*
G01X545315Y71639D02*
G03X545668Y71785I0J500D01*
G01X543672Y70489D02*
X545315D01*
G01X543671Y71639D02*
X545315D01*
G01X546078Y72402D02*
Y125758D01*
G01X547228Y72402D02*
Y125413D01*
G01X545932Y72049D02*
G03X546078Y72402I-354J353D01*
G01X546746Y71236D02*
G03X547228Y72402I-1168J1165D01*
G01X545668Y71785D02*
X545932Y72049D01*
G01X546482Y70971D02*
X546746Y71236D01*
G01X545315Y71639D02*
G03X545668Y71785I0J500D01*
G01X545315Y70489D02*
G03X546482Y70971I1J1650D01*
G01X543671Y71639D02*
X545315D01*
G01X543672Y70489D02*
X545315D01*
G01X554315Y76339D02*
Y124348D01*
G01X553165Y76339D02*
Y124694D01*
G01X553833Y75173D02*
G03X554315Y76339I-1168J1165D01*
G01X553019Y75986D02*
G03X553165Y76339I-354J353D01*
G01X553569Y74908D02*
X553833Y75173D01*
G01X552755Y75722D02*
X553019Y75986D01*
G01X552402Y74426D02*
G03X553569Y74908I1J1650D01*
G01X552402Y75576D02*
G03X552755Y75722I0J500D01*
G01X550759Y74426D02*
X552402D01*
G01X550758Y75576D02*
X552402D01*
G01X553165Y76339D02*
Y124694D01*
G01X554315Y76339D02*
Y124348D01*
G01X553019Y75986D02*
G03X553165Y76339I-354J353D01*
G01X553833Y75173D02*
G03X554315Y76339I-1168J1165D01*
G01X552755Y75722D02*
X553019Y75986D01*
G01X553569Y74908D02*
X553833Y75173D01*
G01X552402Y75576D02*
G03X552755Y75722I0J500D01*
G01X552402Y74426D02*
G03X553569Y74908I1J1650D01*
G01X550758Y75576D02*
X552402D01*
G01X550759Y74426D02*
X552402D01*
G01X526105Y135439D02*
X575394Y168708D01*
G01X550105Y153026D02*
X574943Y169792D01*
G01X525271Y136264D02*
X550105Y153027D01*
G01X522494Y129956D02*
X526105Y135439D01*
G01X517732Y124818D02*
X525271Y136264D01*
G01X518882Y124473D02*
X522494Y129955D01*
G01X517732Y124818D02*
X525271Y136264D01*
G01X550105Y153026D02*
X574943Y169792D01*
G01X526105Y135439D02*
X575394Y168708D01*
G01X525271Y136264D02*
X550105Y153027D01*
G01X526105Y135439D02*
X575394Y168708D01*
G01X517732Y124818D02*
X525271Y136264D01*
G01X522494Y129956D02*
X526105Y135439D01*
G01X518882Y124473D02*
X522494Y129955D01*
G01X534278Y134630D02*
X579669Y165245D01*
G01X533442Y135454D02*
X579218Y166328D01*
G01X525968Y122015D02*
X534278Y134630D01*
G01X533317Y135263D02*
X533442Y135453D01*
G01X524818Y122360D02*
X533317Y135262D01*
G01X533442Y135454D02*
X579218Y166328D01*
G01X534278Y134630D02*
X579669Y165245D01*
G01X533317Y135263D02*
X533442Y135453D01*
G01X525968Y122015D02*
X534278Y134630D01*
G01X524818Y122360D02*
X533317Y135262D01*
G01X525968Y122015D02*
X534278Y134630D01*
G01X537974Y131806D02*
X577629Y158553D01*
G01X537140Y132631D02*
X577175Y159635D01*
G01X533055Y124336D02*
X537974Y131806D01*
G01X531905Y124681D02*
X537140Y132631D01*
G01D02*
X577175Y159635D01*
G01X537974Y131806D02*
X577629Y158553D01*
G01X531905Y124681D02*
X537140Y132631D01*
G01X533055Y124336D02*
X537974Y131806D01*
G01X545308Y131578D02*
X578317Y153845D01*
G01X544474Y132403D02*
X577866Y154929D01*
G01X540142Y123734D02*
X545308Y131578D01*
G01X538992Y124079D02*
X544474Y132403D01*
G01D02*
X577866Y154929D01*
G01X545308Y131578D02*
X578317Y153845D01*
G01X538992Y124079D02*
X544474Y132403D01*
G01X540142Y123734D02*
X545308Y131578D01*
G01X548308Y127054D02*
X560718Y135421D01*
G01X547474Y127879D02*
X560266Y136504D01*
G01X547228Y125413D02*
X548308Y127054D01*
G01X546808Y126867D02*
X547474Y127879D01*
G01X546078Y125758D02*
X546807Y126866D01*
G01X547474Y127879D02*
X560266Y136504D01*
G01X548308Y127054D02*
X560718Y135421D01*
G01X546808Y126867D02*
X547474Y127879D01*
G01X547228Y125413D02*
X548308Y127054D01*
G01X546078Y125758D02*
X546807Y126866D01*
G01X547228Y125413D02*
X548308Y127054D01*
G01X555692Y126436D02*
X561920Y130637D01*
G01X554858Y127261D02*
X558162Y129490D01*
G01X554315Y124348D02*
X555692Y126436D01*
G01X553165Y124694D02*
X554858Y127261D01*
G01X555692Y126436D02*
X561920Y130637D01*
G01X554858Y127261D02*
X558162Y129490D01*
G01X555692Y126436D02*
X561920Y130637D01*
G01X553165Y124694D02*
X554858Y127261D01*
G01X554315Y124348D02*
X555692Y126436D01*
G01X553863Y202357D02*
X699403Y231182D01*
G01X553412Y203441D02*
X699409Y232356D01*
G01X525699Y184743D02*
X553412Y203441D01*
G01D02*
X699409Y232356D01*
G01X553863Y202357D02*
X699403Y231182D01*
G01X525699Y184743D02*
X553412Y203441D01*
G01X547117Y204331D02*
X568499Y218483D01*
G01X547116Y204331D02*
X547117D01*
G01X513737Y182239D02*
X547116Y204331D01*
G01X547117D02*
X568499Y218483D01*
G01X547116Y204331D02*
X547117D01*
G01X513737Y182239D02*
X547116Y204331D01*
G01X561401Y72402D02*
Y124536D01*
G01X560251Y72402D02*
Y124881D01*
G01X560919Y71236D02*
G03X561401Y72402I-1168J1165D01*
G01X560105Y72049D02*
G03X560251Y72402I-354J353D01*
G01X560655Y70971D02*
X560919Y71236D01*
G01X559841Y71785D02*
X560105Y72049D01*
G01X559488Y70489D02*
G03X560655Y70971I1J1650D01*
G01X559488Y71639D02*
G03X559841Y71785I0J500D01*
G01X557845Y70489D02*
X559488D01*
G01X557844Y71639D02*
X559488D01*
G01X560251Y72402D02*
Y124881D01*
G01X561401Y72402D02*
Y124536D01*
G01X560105Y72049D02*
G03X560251Y72402I-354J353D01*
G01X560919Y71236D02*
G03X561401Y72402I-1168J1165D01*
G01X559841Y71785D02*
X560105Y72049D01*
G01X560655Y70971D02*
X560919Y71236D01*
G01X559488Y71639D02*
G03X559841Y71785I0J500D01*
G01X559488Y70489D02*
G03X560655Y70971I1J1650D01*
G01X557844Y71639D02*
X559488D01*
G01X557845Y70489D02*
X559488D01*
G01X569474Y74427D02*
X734603Y107235D01*
G01X569350Y75575D02*
X734609Y108409D01*
G01X565133Y74425D02*
X569472D01*
G01X565133Y75575D02*
X569350D01*
G01D02*
X734609Y108409D01*
G01X569474Y74427D02*
X734603Y107235D01*
G01X565133Y75575D02*
X569350D01*
G01X565133Y74425D02*
X569472D01*
G01X563393Y126633D02*
X626865Y139233D01*
G01X562942Y127716D02*
X626864Y140406D01*
G01X562294Y125893D02*
X563393Y126632D01*
G01X562202Y127218D02*
X562942Y127716D01*
G01X561460Y126718D02*
X562202Y127218D01*
G01X561401Y124536D02*
X562294Y125893D01*
G01X560251Y124881D02*
X561460Y126718D01*
G01X562942Y127716D02*
X626864Y140406D01*
G01X563393Y126633D02*
X626865Y139233D01*
G01X562202Y127218D02*
X562942Y127716D01*
G01X562294Y125893D02*
X563393Y126632D01*
G01X561460Y126718D02*
X562202Y127218D01*
G01X562294Y125893D02*
X563393Y126632D01*
G01X560251Y124881D02*
X561460Y126718D01*
G01X561401Y124536D02*
X562294Y125893D01*
G01X577629Y158553D02*
X620707Y167315D01*
G01X577175Y159635D02*
X620702Y168488D01*
G01X577175Y159635D02*
X620702Y168488D01*
G01X577629Y158553D02*
X620707Y167315D01*
G01X578318Y153846D02*
X620924Y162304D01*
G01X577867Y154929D02*
X620922Y163477D01*
G01X577867Y154929D02*
X620922Y163477D01*
G01X578318Y153846D02*
X620924Y162304D01*
G01X560718Y135421D02*
X634589Y150173D01*
G01X560266Y136504D02*
X634586Y151346D01*
G01X560266Y136504D02*
X634586Y151346D01*
G01X560718Y135421D02*
X634589Y150173D01*
G01X561921Y130638D02*
X632174Y144677D01*
G01X561469Y131721D02*
X632171Y145850D01*
G01X558162Y129490D02*
X561469Y131721D01*
G01D02*
X632171Y145850D01*
G01X561921Y130638D02*
X632174Y144677D01*
G01X558162Y129490D02*
X561469Y131721D01*
G01X575394Y168708D02*
X639856Y181482D01*
G01X574943Y169792D02*
X639854Y182654D01*
G01X574943Y169792D02*
X639854Y182654D01*
G01X575394Y168708D02*
X639856Y181482D01*
G01X579669Y165245D02*
X639579Y177117D01*
G01X579218Y166328D02*
X639577Y178289D01*
G01X579218Y166328D02*
X639577Y178289D01*
G01X579669Y165245D02*
X639579Y177117D01*
G01X590230Y191561D02*
X605282Y199314D01*
G01X590230Y191561D02*
X605282Y199314D01*
G01X560109Y247069D02*
X620061Y287508D01*
G01X560109Y247069D02*
X620061Y287508D01*
G01X568948Y217400D02*
X683760Y240838D01*
G01X568499Y218483D02*
X683763Y242013D01*
G01X568499Y218483D02*
X683763Y242013D01*
G01X568948Y217400D02*
X683760Y240838D01*
G01X626865Y139233D02*
X856838Y94178D01*
G01X626864Y140406D02*
X856836Y95351D01*
G01X626864Y140406D02*
X856836Y95351D01*
G01X626865Y139233D02*
X856838Y94178D01*
G01X620707Y167315D02*
X767718Y138736D01*
G01X620702Y168488D02*
X767716Y139909D01*
G01X620702Y168488D02*
X767716Y139909D01*
G01X620707Y167315D02*
X767718Y138736D01*
G01X620924Y162304D02*
X794334Y128595D01*
G01X620922Y163477D02*
X794332Y129768D01*
G01X620922Y163477D02*
X794332Y129768D01*
G01X620924Y162304D02*
X794334Y128595D01*
G01X634589Y150173D02*
X854258Y107473D01*
G01X634586Y151346D02*
X854256Y108646D01*
G01X634586Y151346D02*
X854256Y108646D01*
G01X634589Y150173D02*
X854258Y107473D01*
G01X632174Y144677D02*
X859413Y100540D01*
G01X632171Y145850D02*
X859410Y101713D01*
G01X632171Y145850D02*
X859410Y101713D01*
G01X632174Y144677D02*
X859413Y100540D01*
G01X639856Y181482D02*
X714066Y167059D01*
G01X639854Y182654D02*
X714082Y168228D01*
G01X639854Y182654D02*
X714082Y168228D01*
G01X639856Y181482D02*
X714066Y167059D01*
G01X639579Y177117D02*
X761280Y153459D01*
G01X639577Y178289D02*
X761279Y154631D01*
G01X639577Y178289D02*
X761279Y154631D01*
G01X639579Y177117D02*
X761280Y153459D01*
G01X605282Y199314D02*
X695856Y217738D01*
G01X604896Y200410D02*
X695859Y218913D01*
G01X604896Y200410D02*
X695859Y218913D01*
G01X605282Y199314D02*
X695856Y217738D01*
G01X614510Y194660D02*
X695424Y211014D01*
G01X614125Y195756D02*
X695425Y212188D01*
G01X614125Y195756D02*
X695425Y212188D01*
G01X614510Y194660D02*
X695424Y211014D01*
G01X618821Y297339D02*
X848595Y342978D01*
G01X618370Y298422D02*
X848601Y344152D01*
G01X618370Y298422D02*
X848601Y344152D01*
G01X618821Y297339D02*
X848595Y342978D01*
G01X619397Y291661D02*
X825691Y332635D01*
G01X618946Y292744D02*
X825697Y333809D01*
G01X618946Y292744D02*
X825697Y333809D01*
G01X619397Y291661D02*
X825691Y332635D01*
G01X620512Y286425D02*
X800162Y322107D01*
G01X620061Y287508D02*
X800168Y323281D01*
G01X620061Y287508D02*
X800168Y323281D01*
G01X620512Y286425D02*
X800162Y322107D01*
G01X612039Y269946D02*
X802299Y307754D01*
G01X611593Y271031D02*
X802312Y308930D01*
G01X611593Y271031D02*
X802312Y308930D01*
G01X612039Y269946D02*
X802299Y307754D01*
G01X695424Y211014D02*
X790112Y191749D01*
G01X695425Y212188D02*
X790115Y192922D01*
G01X695425Y212188D02*
X790115Y192922D01*
G01X695424Y211014D02*
X790112Y191749D01*
G01X699403Y231182D02*
X794165Y211391D01*
G01X699409Y232356D02*
X794170Y212565D01*
G01X699409Y232356D02*
X794170Y212565D01*
G01X699403Y231182D02*
X794165Y211391D01*
G01X695856Y217738D02*
X772021Y201804D01*
G01X695859Y218913D02*
X772028Y202978D01*
G01X695859Y218913D02*
X772028Y202978D01*
G01X695856Y217738D02*
X772021Y201804D01*
G01X683760Y240838D02*
X795741Y217373D01*
G01X683763Y242013D02*
X795747Y218547D01*
G01X683763Y242013D02*
X795747Y218547D01*
G01X683760Y240838D02*
X795741Y217373D01*
G01X734603Y107235D02*
X844940Y84124D01*
G01X734609Y108409D02*
X844946Y85298D01*
G01X734609Y108409D02*
X844946Y85298D01*
G01X734603Y107235D02*
X844940Y84124D01*
G01X714082Y168228D02*
X918998Y202150D01*
G01X714082Y168228D02*
X918998Y202150D01*
G01X714082Y168228D02*
X918998Y202150D01*
G01X714066Y167059D02*
X891669Y196460D01*
G01X714082Y168228D02*
X918998Y202150D01*
G01X714082Y168228D02*
X918998Y202150D01*
G01X714066Y167059D02*
X891669Y196460D01*
G01X761279Y154631D02*
X923765Y186402D01*
G01X761279Y154631D02*
X923765Y186402D01*
G01X761279Y154631D02*
X923765Y186402D01*
G01X761280Y153459D02*
X880583Y176786D01*
G01X761279Y154631D02*
X923765Y186402D01*
G01X761279Y154631D02*
X923765Y186402D01*
G01X761280Y153459D02*
X880583Y176786D01*
G01X767718Y138736D02*
X898948Y164820D01*
G01X767716Y139909D02*
X898723Y165948D01*
G01X767718Y138736D02*
X898948Y164820D01*
G01X767716Y139909D02*
X898723Y165948D01*
G01X767718Y138736D02*
X898948Y164820D01*
G01X794332Y129768D02*
X921000Y154906D01*
G01X794332Y129768D02*
X921000Y154906D01*
G01X794332Y129768D02*
X921000Y154906D01*
G01X794334Y128595D02*
X904100Y150379D01*
G01X794332Y129768D02*
X921000Y154906D01*
G01X794332Y129768D02*
X921000Y154906D01*
G01X794334Y128595D02*
X904100Y150379D01*
G01X794165Y211391D02*
X900842Y232725D01*
G01X794165Y211391D02*
X900842Y232725D01*
G01X772028Y202978D02*
X928274Y233646D01*
G01X772028Y202978D02*
X928274Y233646D01*
G01X772028Y202978D02*
X928274Y233646D01*
G01X772021Y201804D02*
X895864Y226112D01*
G01X772028Y202978D02*
X928274Y233646D01*
G01X772028Y202978D02*
X928274Y233646D01*
G01X772021Y201804D02*
X895864Y226112D01*
G01X790115Y192922D02*
X916529Y217898D01*
G01X790115Y192922D02*
X916529Y217898D01*
G01X790115Y192922D02*
X916529Y217898D01*
G01X790112Y191749D02*
X888102Y211109D01*
G01X790115Y192922D02*
X916529Y217898D01*
G01X790115Y192922D02*
X916529Y217898D01*
G01X790112Y191749D02*
X888102Y211109D01*
G01X794170Y212565D02*
X900353Y233800D01*
G01X794170Y212565D02*
X900353Y233800D01*
G01X795741Y217373D02*
X892178Y236531D01*
G01X795747Y218547D02*
X891689Y237607D01*
G01X795747Y218547D02*
X891689Y237607D01*
G01X795741Y217373D02*
X892178Y236531D01*
G01X791820Y1335681D02*
X1007846Y623730D01*
G01X793009Y1335724D02*
X1006393Y632484D01*
G01X791820Y1335681D02*
X1007846Y623730D01*
G01X791820Y1335681D02*
X1007846Y623730D01*
G01X793009Y1335724D02*
X1006393Y632484D01*
G01X791820Y1335681D02*
X1007846Y623730D01*
G01X818549Y1453801D02*
X791820Y1335681D01*
G01X806369Y1394763D02*
X793009Y1335724D01*
G01X806369Y1394763D02*
X793009Y1335724D01*
G01X818549Y1453801D02*
X791820Y1335681D01*
G01X818549Y1453801D02*
X791820Y1335681D01*
G01X844940Y84124D02*
X917998Y98638D01*
G01X844946Y85298D02*
X917884Y99788D01*
G01X844946Y85298D02*
X917884Y99788D01*
G01X844940Y84124D02*
X917998Y98638D01*
G01X802312Y308930D02*
X928805Y280890D01*
G01X802312Y308930D02*
X928805Y280890D01*
G01X802312Y308930D02*
X928805Y280890D01*
G01X802312Y308930D02*
X928805Y280890D01*
G01X802299Y307754D02*
X856336Y295775D01*
G01X802312Y308930D02*
X928805Y280890D01*
G01X802312Y308930D02*
X928805Y280890D01*
G01X802299Y307754D02*
X856336Y295775D01*
G01X825691Y332635D02*
X912796Y314384D01*
G01X825697Y333809D02*
X911049Y315926D01*
G01X825691Y332635D02*
X912796Y314384D01*
G01X825697Y333809D02*
X911049Y315926D01*
G01X825691Y332635D02*
X912796Y314384D01*
G01X800168Y323281D02*
X927337Y296638D01*
G01X800168Y323281D02*
X927337Y296638D01*
G01X800168Y323281D02*
X927337Y296638D01*
G01X800162Y322107D02*
X899579Y301278D01*
G01X800168Y323281D02*
X927337Y296638D01*
G01X800168Y323281D02*
X927337Y296638D01*
G01X800162Y322107D02*
X899579Y301278D01*
G01X798251Y1337391D02*
X1044793Y524870D01*
G01X799440Y1337434D02*
X1044617Y529413D01*
G01X798251Y1337391D02*
X1044793Y524870D01*
G01X799440Y1337434D02*
X1044617Y529413D01*
G01X798251Y1337391D02*
X1044793Y524870D01*
G01X805878Y1338399D02*
X1046648Y544838D01*
G01X804689Y1338356D02*
X864970Y1139674D01*
G01X805878Y1338399D02*
X1046648Y544838D01*
G01X805878Y1338399D02*
X1046648Y544838D01*
G01X804689Y1338356D02*
X864970Y1139674D01*
G01X825172Y1344255D02*
X1020870Y699244D01*
G01X825172Y1344255D02*
X1020870Y699244D01*
G01X818613Y1343235D02*
X1056980Y557586D01*
G01X819714Y1343568D02*
X1058034Y558076D01*
G01X819714Y1343568D02*
X1058034Y558076D01*
G01X819714Y1343568D02*
X1058034Y558076D01*
G01X818613Y1343235D02*
X1056980Y557586D01*
G01X812082Y1341861D02*
X1053217Y547083D01*
G01X813271Y1341904D02*
X1054271Y547573D01*
G01X813271Y1341904D02*
X1054271Y547573D01*
G01X812082Y1341861D02*
X1053217Y547083D01*
G01X837977Y1348125D02*
X1031629Y709853D01*
G01X837977Y1348125D02*
X1031629Y709853D01*
G01X831851Y1345413D02*
X1026453Y704011D01*
G01X833040Y1345456D02*
X1027507Y704501D01*
G01X833040Y1345456D02*
X1027507Y704501D01*
G01X831851Y1345413D02*
X1026453Y704011D01*
G01X826361Y1344298D02*
X1021924Y699734D01*
G01X826361Y1344298D02*
X1021924Y699734D01*
G01X844360Y1349995D02*
X1035763Y719135D01*
G01X845549Y1350038D02*
X1036817Y719625D01*
G01X868920Y1458521D02*
X844360Y1349995D01*
G01X870097Y1458508D02*
X845549Y1350038D01*
G01D02*
X1036817Y719625D01*
G01X844360Y1349995D02*
X1035763Y719135D01*
G01X870097Y1458508D02*
X845549Y1350038D01*
G01X868920Y1458521D02*
X844360Y1349995D01*
G01X839166Y1348168D02*
X1032683Y710343D01*
G01X864089Y1458387D02*
X839166Y1348168D01*
G01X862910Y1458390D02*
X837977Y1348125D01*
G01X839166Y1348168D02*
X1032683Y710343D01*
G01X862910Y1458390D02*
X837977Y1348125D01*
G01X864089Y1458387D02*
X839166Y1348168D01*
G01X856275Y1453419D02*
X831851Y1345413D01*
G01X857452Y1453406D02*
X833040Y1345456D01*
G01X857452Y1453406D02*
X833040Y1345456D01*
G01X856275Y1453419D02*
X831851Y1345413D01*
G01X849982Y1453903D02*
X825172Y1344255D01*
G01X851161Y1453900D02*
X826361Y1344298D01*
G01X851161Y1453900D02*
X826361Y1344298D01*
G01X849982Y1453903D02*
X825172Y1344255D01*
G01X818525Y1343525D02*
X818612Y1343235D01*
G01X842966Y1451573D02*
X818525Y1343525D01*
G01X844142Y1451558D02*
X819714Y1343568D01*
G01X818525Y1343525D02*
X818612Y1343235D01*
G01X844142Y1451558D02*
X819714Y1343568D01*
G01X842966Y1451573D02*
X818525Y1343525D01*
G01X836994Y1451996D02*
X812082Y1341861D01*
G01X838173Y1451993D02*
X813271Y1341904D01*
G01X838173Y1451993D02*
X813271Y1341904D01*
G01X836994Y1451996D02*
X812082Y1341861D01*
G01X824564Y1453674D02*
X798251Y1337391D01*
G01X825743Y1453671D02*
X799440Y1337434D01*
G01X825743Y1453671D02*
X799440Y1337434D01*
G01X824564Y1453674D02*
X798251Y1337391D01*
G01X830497Y1452397D02*
X804689Y1338356D01*
G01X831676Y1452394D02*
X805878Y1338399D01*
G01X831676Y1452394D02*
X805878Y1338399D01*
G01X830497Y1452397D02*
X804689Y1338356D01*
G01X819701Y1453678D02*
X806369Y1394763D01*
G01X819701Y1453678D02*
X806369Y1394763D01*
G01X835454Y1489166D02*
X842966Y1451573D01*
G01X829022Y1527225D02*
X844142Y1451558D01*
G01X829022Y1527225D02*
X844142Y1451558D01*
G01X829022Y1527225D02*
X844142Y1451558D01*
G01X835454Y1489166D02*
X842966Y1451573D01*
G01X829171Y1487300D02*
X836994Y1451996D01*
G01X822416Y1523104D02*
X838173Y1451993D01*
G01X822416Y1523104D02*
X838173Y1451993D01*
G01X822416Y1523104D02*
X838173Y1451993D01*
G01X829171Y1487300D02*
X836994Y1451996D01*
G01X803867Y1547074D02*
X824564Y1453674D01*
G01X805046Y1547071D02*
X825743Y1453671D01*
G01X805046Y1547071D02*
X825743Y1453671D01*
G01X803867Y1547074D02*
X824564Y1453674D01*
G01X814470Y1524751D02*
X830497Y1452397D01*
G01X815622Y1524868D02*
X831676Y1452394D01*
G01X815622Y1524868D02*
X831676Y1452394D01*
G01X814470Y1524751D02*
X830497Y1452397D01*
G01X797836Y1547273D02*
X818549Y1453801D01*
G01X799015Y1547271D02*
X819701Y1453918D01*
G01X799015Y1547271D02*
X819701Y1453918D01*
G01X797836Y1547273D02*
X818549Y1453801D01*
G01X841470Y1526153D02*
X856275Y1453419D01*
G01X842623Y1526256D02*
X857452Y1453406D01*
G01X842623Y1526256D02*
X857452Y1453406D01*
G01X841470Y1526153D02*
X856275Y1453419D01*
G01X842627Y1487145D02*
X849982Y1453903D01*
G01X836339Y1520886D02*
X851161Y1453900D01*
G01X835187Y1520769D02*
X842627Y1487145D01*
G01X836339Y1520886D02*
X851161Y1453900D01*
G01X836339Y1520886D02*
X851161Y1453900D01*
G01X842627Y1487145D02*
X849982Y1453903D01*
G01X835187Y1520769D02*
X842627Y1487145D01*
G01X827869Y1527125D02*
X835454Y1489166D01*
G01X827869Y1527125D02*
X835454Y1489166D01*
G01X821264Y1522987D02*
X829171Y1487300D01*
G01X821264Y1522987D02*
X829171Y1487300D01*
G01X858073Y1599748D02*
X841472Y1526384D01*
G01X859237Y1599679D02*
X842623Y1526256D01*
G01X859237Y1599679D02*
X842623Y1526256D01*
G01X858073Y1599748D02*
X841472Y1526384D01*
G01X850986Y1590846D02*
X835187Y1521009D01*
G01X852150Y1590777D02*
X836339Y1520886D01*
G01X852150Y1590777D02*
X836339Y1520886D01*
G01X850986Y1590846D02*
X835187Y1521009D01*
G01X843900Y1598184D02*
X827872Y1527354D01*
G01X845064Y1598115D02*
X829022Y1527225D01*
G01X845064Y1598115D02*
X829022Y1527225D01*
G01X843900Y1598184D02*
X827872Y1527354D01*
G01X836813Y1591958D02*
X821264Y1523227D01*
G01X837977Y1591889D02*
X822416Y1523104D01*
G01X837977Y1591889D02*
X822416Y1523104D01*
G01X836813Y1591958D02*
X821264Y1523227D01*
G01X819406Y1615733D02*
X803867Y1547074D01*
G01X820455Y1615154D02*
X805046Y1547071D01*
G01X820455Y1615154D02*
X805046Y1547071D01*
G01X819406Y1615733D02*
X803867Y1547074D01*
G01X829727Y1592423D02*
X814470Y1524991D01*
G01X830891Y1592354D02*
X815622Y1524868D01*
G01X830891Y1592354D02*
X815622Y1524868D01*
G01X829727Y1592423D02*
X814470Y1524991D01*
G01X816265Y1628808D02*
X797836Y1547273D01*
G01X817314Y1628230D02*
X799015Y1547271D01*
G01X817314Y1628230D02*
X799015Y1547271D01*
G01X816265Y1628808D02*
X797836Y1547273D01*
G01X843914Y1642572D02*
Y1598305D01*
G01X845064Y1642572D02*
Y1598115D01*
G01Y1642572D02*
Y1598115D01*
G01X843914Y1642572D02*
Y1598305D01*
G01X836827Y1631807D02*
Y1592079D01*
G01X837977Y1631807D02*
Y1591889D01*
G01Y1631807D02*
Y1591889D01*
G01X836827Y1631807D02*
Y1592079D01*
G01X829741Y1642437D02*
Y1592544D01*
G01X830891Y1642437D02*
Y1592354D01*
G01Y1642437D02*
Y1592354D01*
G01X829741Y1642437D02*
Y1592544D01*
G01X844396Y1643739D02*
G03X843914Y1642572I1168J-1166D01*
G01X845210Y1642925D02*
G03X845064Y1642572I354J-353D01*
G01X845618Y1643126D02*
G03X845265Y1642980I0J-500D01*
G01X845618Y1644276D02*
G03X844452Y1643794I-1J-1650D01*
G01X845210Y1642925D02*
G03X845064Y1642572I354J-353D01*
G01X845618Y1643126D02*
G03X845265Y1642980I0J-500D01*
G01X847325Y1644276D02*
X845618D01*
G01X847327Y1643126D02*
X845618D01*
G01X845210Y1642925D02*
G03X845064Y1642572I354J-353D01*
G01X844396Y1643739D02*
G03X843914Y1642572I1168J-1166D01*
G01X845618Y1644276D02*
G03X844452Y1643794I-1J-1650D01*
G01X845618Y1643126D02*
G03X845265Y1642980I0J-500D01*
G01X844396Y1643739D02*
G03X843914Y1642572I1168J-1166D01*
G01X845618Y1644276D02*
G03X844452Y1643794I-1J-1650D01*
G01X847327Y1643126D02*
X845618D01*
G01X847325Y1644276D02*
X845618D01*
G01X839060Y1634040D02*
G03X836827Y1631807I0J-2233D01*
G01X839060Y1632890D02*
G03X837977Y1631807I0J-1083D01*
G01X840111Y1634040D02*
X839060D01*
G01X840111Y1632890D02*
X839060D01*
G01D02*
G03X837977Y1631807I0J-1083D01*
G01X839060Y1634040D02*
G03X836827Y1631807I0J-2233D01*
G01X840111Y1632890D02*
X839060D01*
G01X840111Y1634040D02*
X839060D01*
G01X822948Y1619274D02*
X819406Y1615733D01*
G01X823761Y1618460D02*
X820455Y1615154D01*
G01X823483Y1619631D02*
G03X822948Y1619274I631J-1525D01*
G01X823923Y1618568D02*
G03X823761Y1618460I191J-462D01*
G01X823751Y1619742D02*
X823483Y1619631D01*
G01X824191Y1618679D02*
X823923Y1618568D01*
G01X824382Y1619867D02*
G03X823751Y1619742I-1J-1649D01*
G01X824382Y1618717D02*
G03X824191Y1618679I0J-499D01*
G01X826065Y1619867D02*
X824382D01*
G01X826067Y1618717D02*
X824382D01*
G01X823761Y1618460D02*
X820455Y1615154D01*
G01X822948Y1619274D02*
X819406Y1615733D01*
G01X823923Y1618568D02*
G03X823761Y1618460I191J-462D01*
G01X823483Y1619631D02*
G03X822948Y1619274I631J-1525D01*
G01X824191Y1618679D02*
X823923Y1618568D01*
G01X823751Y1619742D02*
X823483Y1619631D01*
G01X824382Y1618717D02*
G03X824191Y1618679I0J-499D01*
G01X824382Y1619867D02*
G03X823751Y1619742I-1J-1649D01*
G01X826067Y1618717D02*
X824382D01*
G01X826065Y1619867D02*
X824382D01*
G01X830223Y1643604D02*
G03X829741Y1642437I1168J-1166D01*
G01X831037Y1642790D02*
G03X830891Y1642437I354J-353D01*
G01X830414Y1643794D02*
X830223Y1643604D01*
G01X831227Y1642980D02*
X831037Y1642790D01*
G01X831580Y1644276D02*
G03X830414Y1643794I-1J-1650D01*
G01X831580Y1643126D02*
G03X831227Y1642980I0J-500D01*
G01X833152Y1644276D02*
X831580D01*
G01X833154Y1643126D02*
X831580D01*
G01X831037Y1642790D02*
G03X830891Y1642437I354J-353D01*
G01X830223Y1643604D02*
G03X829741Y1642437I1168J-1166D01*
G01X831227Y1642980D02*
X831037Y1642790D01*
G01X830414Y1643794D02*
X830223Y1643604D01*
G01X831580Y1643126D02*
G03X831227Y1642980I0J-500D01*
G01X831580Y1644276D02*
G03X830414Y1643794I-1J-1650D01*
G01X833154Y1643126D02*
X831580D01*
G01X833152Y1644276D02*
X831580D01*
G01X821497Y1634040D02*
X816265Y1628808D01*
G01X821974Y1632890D02*
X817314Y1628230D01*
G01X825938Y1634040D02*
X821497D01*
G01X825938Y1632890D02*
X821974D01*
G01D02*
X817314Y1628230D01*
G01X821497Y1634040D02*
X816265Y1628808D01*
G01X825938Y1632890D02*
X821974D01*
G01X825938Y1634040D02*
X821497D01*
G01X856838Y94178D02*
X918913Y106512D01*
G01X856836Y95351D02*
X918799Y107662D01*
G01X856836Y95351D02*
X918799Y107662D01*
G01X856838Y94178D02*
X918913Y106512D01*
G01X854258Y107473D02*
X928651Y122260D01*
G01X854256Y108646D02*
X928537Y123410D01*
G01X854256Y108646D02*
X928537Y123410D01*
G01X854258Y107473D02*
X928651Y122260D01*
G01X859413Y100540D02*
X928636Y114386D01*
G01X859410Y101713D02*
X928522Y115536D01*
G01X859410Y101713D02*
X928522Y115536D01*
G01X859413Y100540D02*
X928636Y114386D01*
G01X894382Y196909D02*
X896010Y197179D01*
G01X894382Y196909D02*
X896010Y197179D01*
G01X891918Y179003D02*
X923877Y185252D01*
G01X887600Y178158D02*
X889220Y178475D01*
G01X883282Y177314D02*
X884901Y177631D01*
G01X891918Y179003D02*
X923877Y185252D01*
G01X887600Y178158D02*
X889220Y178475D01*
G01X883282Y177314D02*
X884901Y177631D01*
G01X890800Y211642D02*
X892418Y211962D01*
G01X890800Y211642D02*
X892418Y211962D01*
G01X891689Y237607D02*
X927438Y265142D01*
G01X891689Y237607D02*
X927438Y265142D01*
G01X891689Y237607D02*
X927438Y265142D01*
G01X891689Y237607D02*
X927438Y265142D01*
G01X891689Y237607D02*
X927438Y265142D01*
G01X891689Y237607D02*
X927438Y265142D01*
G01X891689Y237607D02*
X927438Y265142D01*
G01X892178Y236531D02*
X902012Y244106D01*
G01X891689Y237607D02*
X927438Y265142D01*
G01X891689Y237607D02*
X927438Y265142D01*
G01X892178Y236531D02*
X902012Y244106D01*
G01X856336Y295775D02*
X903511Y285319D01*
G01X856336Y295775D02*
X903511Y285319D01*
G01X848601Y344152D02*
X925052Y328134D01*
G01X848601Y344152D02*
X925052Y328134D01*
G01X848601Y344152D02*
X925052Y328134D01*
G01X881736Y336033D02*
X905036Y331152D01*
G01X848601Y344152D02*
X925052Y328134D01*
G01X848595Y342978D02*
X881736Y336033D01*
G01X848601Y344152D02*
X925052Y328134D01*
G01X848601Y344152D02*
X925052Y328134D01*
G01X881736Y336033D02*
X905036Y331152D01*
G01X848595Y342978D02*
X881736Y336033D01*
G01X905963Y394095D02*
X866271Y573236D01*
G01X904885Y393643D02*
X865092Y573239D01*
G01X904885Y393643D02*
X865092Y573239D01*
G01X905963Y394095D02*
X866271Y573236D01*
G01X897478Y484179D02*
X877858Y571386D01*
G01X897478Y484179D02*
X877858Y571386D01*
G01X911395Y396369D02*
X872401Y572351D01*
G01X910317Y395917D02*
X871222Y572354D01*
G01X910317Y395917D02*
X871222Y572354D01*
G01X911395Y396369D02*
X872401Y572351D01*
G01X918165Y397479D02*
X879037Y571385D01*
G01X918165Y397479D02*
X879037Y571385D01*
G01X918165Y397479D02*
X879037Y571385D01*
G01X925436Y394034D02*
X886147Y571350D01*
G01X924358Y393582D02*
X884968Y571353D01*
G01X924358Y393582D02*
X884968Y571353D01*
G01X925436Y394034D02*
X886147Y571350D01*
G01X879037Y571385D02*
X889616Y618107D01*
G01X877858Y571386D02*
X888539Y618563D01*
G01X877858Y571386D02*
X888539Y618563D01*
G01X879037Y571385D02*
X889616Y618107D01*
G01X886147Y571350D02*
X895238Y611510D01*
G01X884968Y571353D02*
X894161Y611965D01*
G01X884968Y571353D02*
X894161Y611965D01*
G01X886147Y571350D02*
X895238Y611510D01*
G01X865092Y573239D02*
X879133Y635294D01*
G01X866271Y573236D02*
X873241Y604040D01*
G01X865092Y573239D02*
X879133Y635294D01*
G01X865092Y573239D02*
X879133Y635294D01*
G01X866271Y573236D02*
X873241Y604040D01*
G01X871222Y572354D02*
X883701Y627497D01*
G01X872401Y572351D02*
X878590Y599699D01*
G01X871222Y572354D02*
X883701Y627497D01*
G01X871222Y572354D02*
X883701Y627497D01*
G01X872401Y572351D02*
X878590Y599699D01*
G01X888539Y618563D02*
X924459Y673656D01*
G01X888539Y618563D02*
X924459Y673656D01*
G01X888539Y618563D02*
X924459Y673656D01*
G01X889616Y618107D02*
X916570Y659450D01*
G01X888539Y618563D02*
X924459Y673656D01*
G01X888539Y618563D02*
X924459Y673656D01*
G01X889616Y618107D02*
X916570Y659450D01*
G01X894161Y611965D02*
X923533Y657198D01*
G01X894161Y611965D02*
X923533Y657198D01*
G01X894161Y611965D02*
X923533Y657198D01*
G01X894161Y611965D02*
X923533Y657198D01*
G01X894161Y611965D02*
X923533Y657198D01*
G01X879133Y635294D02*
X924379Y704959D01*
G01X879133Y635294D02*
X924379Y704959D01*
G01X879133Y635294D02*
X924379Y704959D01*
G01X880210Y634839D02*
X916511Y690733D01*
G01X879133Y635294D02*
X924379Y704959D01*
G01X873242Y604040D02*
X880210Y634839D01*
G01X879133Y635294D02*
X924379Y704959D01*
G01X880210Y634839D02*
X916511Y690733D01*
G01X873242Y604040D02*
X880210Y634839D01*
G01X883701Y627497D02*
X923354Y688556D01*
G01X883701Y627497D02*
X923354Y688556D01*
G01X883701Y627497D02*
X923354Y688556D01*
G01X884778Y627042D02*
X916690Y676181D01*
G01X883701Y627497D02*
X923354Y688556D01*
G01X878591Y599699D02*
X884778Y627042D01*
G01X883701Y627497D02*
X923354Y688556D01*
G01X884778Y627042D02*
X916690Y676181D01*
G01X878591Y599699D02*
X884778Y627042D01*
G01X864970Y1139674D02*
X1045594Y544348D01*
G01X864970Y1139674D02*
X1045594Y544348D01*
G01X855781Y1523358D02*
X868920Y1458521D01*
G01X856934Y1523459D02*
X870097Y1458508D01*
G01X856934Y1523459D02*
X870097Y1458508D01*
G01X855781Y1523358D02*
X868920Y1458521D01*
G01X849828Y1522831D02*
X864089Y1458387D01*
G01X848676Y1522714D02*
X862910Y1458390D01*
G01X848676Y1522714D02*
X862910Y1458390D01*
G01X849828Y1522831D02*
X864089Y1458387D01*
G01X872246Y1596356D02*
X855784Y1523589D01*
G01X873410Y1596287D02*
X856935Y1523461D01*
G01X873410Y1596287D02*
X856935Y1523461D01*
G01X872246Y1596356D02*
X855784Y1523589D01*
G01X866324Y1595740D02*
X849828Y1522831D01*
G01X865160Y1595809D02*
X848676Y1522954D01*
G01X865160Y1595809D02*
X848676Y1522954D01*
G01X866324Y1595740D02*
X849828Y1522831D01*
G01X872260Y1641678D02*
Y1596477D01*
G01X873410Y1641678D02*
Y1596287D01*
G01Y1641678D02*
Y1596287D01*
G01X872260Y1641678D02*
Y1596477D01*
G01X866324Y1631807D02*
Y1595740D01*
G01X865174Y1631807D02*
Y1595930D01*
G01Y1631807D02*
Y1595930D01*
G01X866324Y1631807D02*
Y1595740D01*
G01X858087Y1641579D02*
Y1599869D01*
G01X859237Y1641579D02*
Y1599679D01*
G01Y1641579D02*
Y1599679D01*
G01X858087Y1641579D02*
Y1599869D01*
G01X851000Y1631807D02*
Y1590967D01*
G01X852150Y1631807D02*
Y1590777D01*
G01Y1631807D02*
Y1590777D01*
G01X851000Y1631807D02*
Y1590967D01*
G01X874858Y1644276D02*
G03X872260Y1641678I0J-2598D01*
G01X874858Y1643126D02*
G03X873410Y1641678I0J-1448D01*
G01X875671Y1644276D02*
X874858D01*
G01X875673Y1643126D02*
X874858D01*
G01D02*
G03X873410Y1641678I0J-1448D01*
G01X874858Y1644276D02*
G03X872260Y1641678I0J-2598D01*
G01X875673Y1643126D02*
X874858D01*
G01X875671Y1644276D02*
X874858D01*
G01X867407Y1632890D02*
G03X866324Y1631807I0J-1083D01*
G01X867407Y1634040D02*
G03X865174Y1631807I0J-2233D01*
G01X868458Y1632890D02*
X867407D01*
G01X868458Y1634040D02*
X867407D01*
G01D02*
G03X865174Y1631807I0J-2233D01*
G01X867407Y1632890D02*
G03X866324Y1631807I0J-1083D01*
G01X868458Y1634040D02*
X867407D01*
G01X868458Y1632890D02*
X867407D01*
G01X860784Y1644276D02*
G03X858087Y1641579I0J-2697D01*
G01X860784Y1643126D02*
G03X859237Y1641579I0J-1547D01*
G01X861498Y1644276D02*
X860784D01*
G01X861500Y1643126D02*
X860784D01*
G01D02*
G03X859237Y1641579I0J-1547D01*
G01X860784Y1644276D02*
G03X858087Y1641579I0J-2697D01*
G01X861500Y1643126D02*
X860784D01*
G01X861498Y1644276D02*
X860784D01*
G01X853233Y1634040D02*
G03X851000Y1631807I0J-2233D01*
G01X853233Y1632890D02*
G03X852150Y1631807I0J-1083D01*
G01X854284Y1634040D02*
X853233D01*
G01X854284Y1632890D02*
X853233D01*
G01D02*
G03X852150Y1631807I0J-1083D01*
G01X853233Y1634040D02*
G03X851000Y1631807I0J-2233D01*
G01X854284Y1632890D02*
X853233D01*
G01X854284Y1634040D02*
X853233D01*
G01X935138Y110449D02*
X948917D01*
G01X934661Y111599D02*
X948440D01*
G01X931201Y106512D02*
X935138Y110449D01*
G01X930724Y107662D02*
X934661Y111599D01*
G01X918913Y106512D02*
X931201D01*
G01X918799Y107662D02*
X930724D01*
G01X934661Y111599D02*
X948440D01*
G01X935138Y110449D02*
X948917D01*
G01X930724Y107662D02*
X934661Y111599D01*
G01X931201Y106512D02*
X935138Y110449D01*
G01X918799Y107662D02*
X930724D01*
G01X918913Y106512D02*
X931201D01*
G01X935138Y102575D02*
X948917D01*
G01X934661Y103725D02*
X948440D01*
G01X931201Y98638D02*
X935138Y102575D01*
G01X930724Y99788D02*
X934661Y103725D01*
G01X917998Y98638D02*
X931201D01*
G01X917884Y99788D02*
X930724D01*
G01X934661Y103725D02*
X948440D01*
G01X935138Y102575D02*
X948917D01*
G01X930724Y99788D02*
X934661Y103725D01*
G01X931201Y98638D02*
X935138Y102575D01*
G01X917884Y99788D02*
X930724D01*
G01X917998Y98638D02*
X931201D01*
G01Y114386D02*
X935138Y118323D01*
G01X930724Y115536D02*
X934661Y119473D01*
G01X928636Y114386D02*
X931201D01*
G01X928522Y115536D02*
X930724D01*
G01D02*
X934661Y119473D01*
G01X931201Y114386D02*
X935138Y118323D01*
G01X928522Y115536D02*
X930724D01*
G01X928636Y114386D02*
X931201D01*
G01X935812Y157693D02*
X948370D01*
G01X935335Y158843D02*
X948369D01*
G01X931875Y153756D02*
X935812Y157693D01*
G01X931398Y154906D02*
X935335Y158843D01*
G01X921114Y153756D02*
X931875D01*
G01X921000Y154906D02*
X931398D01*
G01X915429Y152628D02*
X921114Y153756D01*
G01X911113Y151771D02*
X912732Y152092D01*
G01X906797Y150915D02*
X908416Y151236D01*
G01X935335Y158843D02*
X948369D01*
G01X935812Y157693D02*
X948370D01*
G01X931398Y154906D02*
X935335Y158843D01*
G01X931875Y153756D02*
X935812Y157693D01*
G01X921000Y154906D02*
X931398D01*
G01X921114Y153756D02*
X931875D01*
G01X915429Y152628D02*
X921114Y153756D01*
G01X911113Y151771D02*
X912732Y152092D01*
G01X906797Y150915D02*
X908416Y151236D01*
G01X935138Y126197D02*
X948917D01*
G01X934661Y127347D02*
X948440D01*
G01X931201Y122260D02*
X935138Y126197D01*
G01X930724Y123410D02*
X934661Y127347D01*
G01X928651Y122260D02*
X931201D01*
G01X928537Y123410D02*
X930724D01*
G01X934661Y127347D02*
X948440D01*
G01X935138Y126197D02*
X948917D01*
G01X930724Y123410D02*
X934661Y127347D01*
G01X931201Y122260D02*
X935138Y126197D01*
G01X928537Y123410D02*
X930724D01*
G01X928651Y122260D02*
X931201D01*
G01X935138Y118323D02*
X948917D01*
G01X934661Y119473D02*
X948440D01*
G01X934661D02*
X948440D01*
G01X935138Y118323D02*
X948917D01*
G01X935210Y204937D02*
X948370D01*
G01X934733Y206087D02*
X948369D01*
G01X931273Y201000D02*
X935210Y204937D01*
G01X930796Y202150D02*
X934733Y206087D01*
G01X919093Y201000D02*
X931273D01*
G01X918998Y202150D02*
X930796D01*
G01X903064Y198346D02*
X919093Y201000D01*
G01X898723Y197628D02*
X900351Y197897D01*
G01X934733Y206087D02*
X948369D01*
G01X935210Y204937D02*
X948370D01*
G01X930796Y202150D02*
X934733Y206087D01*
G01X931273Y201000D02*
X935210Y204937D01*
G01X918998Y202150D02*
X930796D01*
G01X919093Y201000D02*
X931273D01*
G01X903064Y198346D02*
X919093Y201000D01*
G01X898723Y197628D02*
X900351Y197897D01*
G01X935812Y189189D02*
X948370D01*
G01X935335Y190339D02*
X948369D01*
G01X931875Y185252D02*
X935812Y189189D01*
G01X931398Y186402D02*
X935335Y190339D01*
G01X923877Y185252D02*
X931875D01*
G01X923765Y186402D02*
X931398D01*
G01X935335Y190339D02*
X948369D01*
G01X935812Y189189D02*
X948370D01*
G01X931398Y186402D02*
X935335Y190339D01*
G01X931875Y185252D02*
X935812Y189189D01*
G01X923765Y186402D02*
X931398D01*
G01X923877Y185252D02*
X931875D01*
G01X935442Y173441D02*
X948370D01*
G01X934965Y174591D02*
X948369D01*
G01X931505Y169504D02*
X935442Y173441D01*
G01X931028Y170654D02*
X934965Y174591D01*
G01X922512Y169504D02*
X931505D01*
G01X922398Y170654D02*
X931028D01*
G01X910277Y167072D02*
X922512Y169504D01*
G01X898724Y165948D02*
X922398Y170654D01*
G01X905961Y166214D02*
X907579Y166536D01*
G01X898724Y165948D02*
X922398Y170654D01*
G01X901645Y165356D02*
X903264Y165678D01*
G01X898724Y165948D02*
X922398Y170654D01*
G01X898723Y165948D02*
X898724D01*
G01X934965Y174591D02*
X948369D01*
G01X935442Y173441D02*
X948370D01*
G01X931028Y170654D02*
X934965Y174591D01*
G01X931505Y169504D02*
X935442Y173441D01*
G01X922398Y170654D02*
X931028D01*
G01X922512Y169504D02*
X931505D01*
G01X898724Y165948D02*
X922398Y170654D01*
G01X910277Y167072D02*
X922512Y169504D01*
G01X905961Y166214D02*
X907579Y166536D01*
G01X901645Y165356D02*
X903264Y165678D01*
G01X898723Y165948D02*
X898724D01*
G01X895116Y212495D02*
X896735Y212815D01*
G01X895116Y212495D02*
X896735Y212815D01*
G01X935210Y252181D02*
X948370D01*
G01X934733Y253331D02*
X948369D01*
G01X931273Y248244D02*
X935210Y252181D01*
G01X930796Y249394D02*
X934733Y253331D01*
G01X920991Y248244D02*
X931273D01*
G01X920599Y249394D02*
X930796D01*
G01X918746Y246515D02*
X920991Y248244D01*
G01X900353Y233800D02*
X920599Y249394D01*
G01X916568Y244837D02*
X917339Y244737D01*
G01X900353Y233800D02*
X920599Y249394D01*
G01X915260Y243830D02*
X916568Y244837D01*
G01X900353Y233800D02*
X920599Y249394D01*
G01X913082Y242152D02*
X913853Y242052D01*
G01X900353Y233800D02*
X920599Y249394D01*
G01X911774Y241145D02*
X913082Y242152D01*
G01X900353Y233800D02*
X920599Y249394D01*
G01X909596Y239467D02*
X910367Y239367D01*
G01X900353Y233800D02*
X920599Y249394D01*
G01X905326Y236178D02*
X909596Y239467D01*
G01X900353Y233800D02*
X920599Y249394D01*
G01X900842Y232725D02*
X905326Y236178D01*
G01X900353Y233800D02*
X920599Y249394D01*
G01X934733Y253331D02*
X948369D01*
G01X935210Y252181D02*
X948370D01*
G01X930796Y249394D02*
X934733Y253331D01*
G01X931273Y248244D02*
X935210Y252181D01*
G01X920599Y249394D02*
X930796D01*
G01X920991Y248244D02*
X931273D01*
G01X900353Y233800D02*
X920599Y249394D01*
G01X918746Y246515D02*
X920991Y248244D01*
G01X916568Y244837D02*
X917339Y244737D01*
G01X915260Y243830D02*
X916568Y244837D01*
G01X913082Y242152D02*
X913853Y242052D01*
G01X911774Y241145D02*
X913082Y242152D01*
G01X909596Y239467D02*
X910367Y239367D01*
G01X905326Y236178D02*
X909596Y239467D01*
G01X900842Y232725D02*
X905326Y236178D01*
G01X935210Y236433D02*
X948370D01*
G01X934733Y237583D02*
X948369D01*
G01X931273Y232496D02*
X935210Y236433D01*
G01X930796Y233646D02*
X934733Y237583D01*
G01X928386Y232496D02*
X931273D01*
G01X928274Y233646D02*
X930796D01*
G01X907198Y228337D02*
X928386Y232496D01*
G01X902880Y227489D02*
X904499Y227807D01*
G01X898563Y226642D02*
X900182Y226959D01*
G01X934733Y237583D02*
X948369D01*
G01X935210Y236433D02*
X948370D01*
G01X930796Y233646D02*
X934733Y237583D01*
G01X931273Y232496D02*
X935210Y236433D01*
G01X928274Y233646D02*
X930796D01*
G01X928386Y232496D02*
X931273D01*
G01X907198Y228337D02*
X928386Y232496D01*
G01X902880Y227489D02*
X904499Y227807D01*
G01X898563Y226642D02*
X900182Y226959D01*
G01X935210Y220685D02*
X948370D01*
G01X934733Y221835D02*
X948369D01*
G01X931273Y216748D02*
X935210Y220685D01*
G01X930796Y217898D02*
X934733Y221835D01*
G01X916642Y216748D02*
X931273D01*
G01X916529Y217898D02*
X930796D01*
G01X899433Y213348D02*
X916642Y216748D01*
G01X934733Y221835D02*
X948369D01*
G01X935210Y220685D02*
X948370D01*
G01X930796Y217898D02*
X934733Y221835D01*
G01X931273Y216748D02*
X935210Y220685D01*
G01X916529Y217898D02*
X930796D01*
G01X916642Y216748D02*
X931273D01*
G01X899433Y213348D02*
X916642Y216748D01*
G01X920782Y258563D02*
X927830Y263992D01*
G01X918603Y256885D02*
X919375Y256785D01*
G01X917296Y255878D02*
X918603Y256885D01*
G01X915117Y254200D02*
X915889Y254100D01*
G01X913810Y253193D02*
X915117Y254200D01*
G01X911632Y251515D02*
X912403Y251415D01*
G01X902012Y244106D02*
X911632Y251515D01*
G01X920782Y258563D02*
X927830Y263992D01*
G01X918603Y256885D02*
X919375Y256785D01*
G01X917296Y255878D02*
X918603Y256885D01*
G01X915117Y254200D02*
X915889Y254100D01*
G01X913810Y253193D02*
X915117Y254200D01*
G01X911632Y251515D02*
X912403Y251415D01*
G01X902012Y244106D02*
X911632Y251515D01*
G01X935812Y299425D02*
X948370D01*
G01X935335Y300575D02*
X948369D01*
G01X931875Y295488D02*
X935812Y299425D01*
G01X931398Y296638D02*
X935335Y300575D01*
G01X927217Y295488D02*
X931875D01*
G01X927337Y296638D02*
X931398D01*
G01X910884Y298910D02*
X927217Y295488D01*
G01X906578Y299812D02*
X908192Y299474D01*
G01X902271Y300714D02*
X903886Y300376D01*
G01X935335Y300575D02*
X948369D01*
G01X935812Y299425D02*
X948370D01*
G01X931398Y296638D02*
X935335Y300575D01*
G01X931875Y295488D02*
X935812Y299425D01*
G01X927337Y296638D02*
X931398D01*
G01X927217Y295488D02*
X931875D01*
G01X910884Y298910D02*
X927217Y295488D01*
G01X906578Y299812D02*
X908192Y299474D01*
G01X902271Y300714D02*
X903886Y300376D01*
G01X935210Y283677D02*
X948370D01*
G01X934733Y284827D02*
X948369D01*
G01X931273Y279740D02*
X935210Y283677D01*
G01X930796Y280890D02*
X934733Y284827D01*
G01X928679Y279740D02*
X931273D01*
G01X928805Y280890D02*
X930796D01*
G01X914787Y282819D02*
X928679Y279740D01*
G01X910491Y283771D02*
X912102Y283414D01*
G01X906195Y284724D02*
X907806Y284367D01*
G01X934733Y284827D02*
X948369D01*
G01X935210Y283677D02*
X948370D01*
G01X930796Y280890D02*
X934733Y284827D01*
G01X931273Y279740D02*
X935210Y283677D01*
G01X928805Y280890D02*
X930796D01*
G01X928679Y279740D02*
X931273D01*
G01X914787Y282819D02*
X928679Y279740D01*
G01X910491Y283771D02*
X912102Y283414D01*
G01X906195Y284724D02*
X907806Y284367D01*
G01X935210Y267929D02*
X948370D01*
G01X934733Y269079D02*
X948369D01*
G01X931273Y263992D02*
X935210Y267929D01*
G01X930796Y265142D02*
X934733Y269079D01*
G01X927830Y263992D02*
X931273D01*
G01X927438Y265142D02*
X930796D01*
G01X934733Y269079D02*
X948369D01*
G01X935210Y267929D02*
X948370D01*
G01X930796Y265142D02*
X934733Y269079D01*
G01X931273Y263992D02*
X935210Y267929D01*
G01X927438Y265142D02*
X930796D01*
G01X927830Y263992D02*
X931273D01*
G01X954018Y347514D02*
X913871Y379803D01*
G01X954018Y347514D02*
X913871Y379803D01*
G01X935812Y330921D02*
X948370D01*
G01X935335Y332071D02*
X948369D01*
G01X931875Y326984D02*
X935812Y330921D01*
G01X931398Y328134D02*
X935335Y332071D01*
G01X924932Y326984D02*
X931875D01*
G01X925052Y328134D02*
X931398D01*
G01X916341Y328784D02*
X924932Y326984D01*
G01X912034Y329686D02*
X913649Y329348D01*
G01X907728Y330588D02*
X909343Y330250D01*
G01X935335Y332071D02*
X948369D01*
G01X935812Y330921D02*
X948370D01*
G01X931398Y328134D02*
X935335Y332071D01*
G01X931875Y326984D02*
X935812Y330921D01*
G01X925052Y328134D02*
X931398D01*
G01X924932Y326984D02*
X931875D01*
G01X916341Y328784D02*
X924932Y326984D01*
G01X912034Y329686D02*
X913649Y329348D01*
G01X907728Y330588D02*
X909343Y330250D01*
G01X935673Y315173D02*
X948370D01*
G01X935196Y316323D02*
X948369D01*
G01X931736Y311236D02*
X935673Y315173D01*
G01X931259Y312386D02*
X935196Y316323D01*
G01X927818Y311236D02*
X931736D01*
G01X927938Y312386D02*
X931259D01*
G01X924101Y312015D02*
X927818Y311236D01*
G01X914378Y315227D02*
X927938Y312386D01*
G01X919795Y312917D02*
X921410Y312579D01*
G01X914378Y315227D02*
X927938Y312386D01*
G01X915488Y313819D02*
X917103Y313481D01*
G01X914378Y315227D02*
X927938Y312386D01*
G01X911049Y315926D02*
X913033Y315510D01*
G01X935196Y316323D02*
X948369D01*
G01X935673Y315173D02*
X948370D01*
G01X931259Y312386D02*
X935196Y316323D01*
G01X931736Y311236D02*
X935673Y315173D01*
G01X927938Y312386D02*
X931259D01*
G01X927818Y311236D02*
X931736D01*
G01X914378Y315227D02*
X927938Y312386D01*
G01X924101Y312015D02*
X927818Y311236D01*
G01X919795Y312917D02*
X921410Y312579D01*
G01X915488Y313819D02*
X917103Y313481D01*
G01X911049Y315926D02*
X913033Y315510D01*
G01X917088Y397025D02*
X897478Y484179D01*
G01X923639Y389050D02*
X918165Y397479D01*
G01X922674Y388423D02*
X917088Y397025D01*
G01X927045Y383807D02*
X923639Y389050D01*
G01X926181Y383026D02*
X922674Y388423D01*
G01X962214Y355527D02*
X927045Y383807D01*
G01X961357Y354739D02*
X926181Y383026D01*
G01X917088Y397025D02*
X897478Y484179D01*
G01X922674Y388423D02*
X917088Y397025D01*
G01X923639Y389050D02*
X918165Y397479D01*
G01X926181Y383026D02*
X922674Y388423D01*
G01X927045Y383807D02*
X923639Y389050D01*
G01X961357Y354739D02*
X926181Y383026D01*
G01X962214Y355527D02*
X927045Y383807D01*
G01X928317Y389599D02*
X925436Y394034D01*
G01X927452Y388818D02*
X924358Y393582D01*
G01X964706Y360336D02*
X928317Y389599D01*
G01X963847Y359551D02*
X927452Y388818D01*
G01D02*
X924358Y393582D01*
G01X928317Y389599D02*
X925436Y394034D01*
G01X963847Y359551D02*
X927452Y388818D01*
G01X964706Y360336D02*
X928317Y389599D01*
G01X914736Y380584D02*
X905963Y394095D01*
G01X913871Y379803D02*
X904885Y393643D01*
G01X954857Y348316D02*
X914736Y380584D01*
G01X913871Y379803D02*
X904885Y393643D01*
G01X914736Y380584D02*
X905963Y394095D01*
G01X954857Y348316D02*
X914736Y380584D01*
G01X920117Y382934D02*
X911395Y396369D01*
G01X919252Y382153D02*
X910317Y395917D01*
G01X959186Y351516D02*
X920117Y382934D01*
G01X958330Y350727D02*
X919252Y382153D01*
G01D02*
X910317Y395917D01*
G01X920117Y382934D02*
X911395Y396369D01*
G01X958330Y350727D02*
X919252Y382153D01*
G01X959186Y351516D02*
X920117Y382934D01*
G01X918099Y646715D02*
X918997Y648099D01*
G01X895238Y611510D02*
X916601Y644409D01*
G01X918099Y646715D02*
X918997Y648099D01*
G01X895238Y611510D02*
X916601Y644409D01*
G01X935433Y678558D02*
X948370D01*
G01X934956Y679708D02*
X948369D01*
G01X931496Y674621D02*
X935433Y678558D01*
G01X931019Y675771D02*
X934956Y679708D01*
G01X927595Y674621D02*
X931496D01*
G01X927203Y675771D02*
X931019D01*
G01X925316Y672864D02*
X927595Y674621D01*
G01X924459Y673656D02*
X927203Y675771D01*
G01X922878Y669125D02*
X925316Y672864D01*
G01X920475Y665439D02*
X921376Y666821D01*
G01X918072Y661754D02*
X918973Y663136D01*
G01X934956Y679708D02*
X948369D01*
G01X935433Y678558D02*
X948370D01*
G01X931019Y675771D02*
X934956Y679708D01*
G01X931496Y674621D02*
X935433Y678558D01*
G01X927203Y675771D02*
X931019D01*
G01X927595Y674621D02*
X931496D01*
G01X924459Y673656D02*
X927203Y675771D01*
G01X925316Y672864D02*
X927595Y674621D01*
G01X922878Y669125D02*
X925316Y672864D01*
G01X920475Y665439D02*
X921376Y666821D01*
G01X918072Y661754D02*
X918973Y663136D01*
G01X935437Y662810D02*
X948370D01*
G01X934960Y663960D02*
X948369D01*
G01X931500Y658873D02*
X935437Y662810D01*
G01X931023Y660023D02*
X934960Y663960D01*
G01X927594Y658873D02*
X931500D01*
G01X927938Y660023D02*
X931023D01*
G01X927207Y660027D02*
X927934D01*
G01X924792Y656716D02*
X927594Y658873D01*
G01X923534Y657199D02*
X927207Y660027D01*
G01X924392Y656407D02*
X924792Y656716D01*
G01X923534Y657199D02*
X927207Y660027D01*
G01X922891Y654096D02*
X924392Y656407D01*
G01X920495Y650405D02*
X921393Y651789D01*
G01X934960Y663960D02*
X948369D01*
G01X935437Y662810D02*
X948370D01*
G01X931023Y660023D02*
X934960Y663960D01*
G01X931500Y658873D02*
X935437Y662810D01*
G01X927938Y660023D02*
X931023D01*
G01X927594Y658873D02*
X931500D01*
G01X927207Y660027D02*
X927934D01*
G01X927594Y658873D02*
X931500D01*
G01X923534Y657199D02*
X927207Y660027D01*
G01X924792Y656716D02*
X927594Y658873D01*
G01X924392Y656407D02*
X924792Y656716D01*
G01X922891Y654096D02*
X924392Y656407D01*
G01X920495Y650405D02*
X921393Y651789D01*
G01X918009Y693039D02*
X918908Y694423D01*
G01X918009Y693039D02*
X918908Y694423D01*
G01X935433Y694306D02*
X948370D01*
G01X934956Y695456D02*
X948369D01*
G01X931496Y690369D02*
X935433Y694306D01*
G01X931019Y691519D02*
X934956Y695456D01*
G01X927593Y690369D02*
X931496D01*
G01X927201Y691519D02*
X931019D01*
G01X924212Y687764D02*
X927593Y690369D01*
G01X923354Y688556D02*
X927201Y691519D01*
G01X922980Y685867D02*
X924212Y687764D01*
G01X920584Y682177D02*
X921482Y683561D01*
G01X918187Y678487D02*
X919086Y679871D01*
G01X934956Y695456D02*
X948369D01*
G01X935433Y694306D02*
X948370D01*
G01X931019Y691519D02*
X934956Y695456D01*
G01X931496Y690369D02*
X935433Y694306D01*
G01X927201Y691519D02*
X931019D01*
G01X927593Y690369D02*
X931496D01*
G01X923354Y688556D02*
X927201Y691519D01*
G01X924212Y687764D02*
X927593Y690369D01*
G01X922980Y685867D02*
X924212Y687764D01*
G01X920584Y682177D02*
X921482Y683561D01*
G01X918187Y678487D02*
X919086Y679871D01*
G01X935433Y710054D02*
X948370D01*
G01X934956Y711204D02*
X948369D01*
G01X931496Y706117D02*
X935433Y710054D01*
G01X931019Y707267D02*
X934956Y711204D01*
G01X927766Y706117D02*
X931496D01*
G01X927374Y707267D02*
X931019D01*
G01X925237Y704168D02*
X927766Y706117D01*
G01X925168Y705567D02*
X927374Y707267D01*
G01X924379Y704959D02*
X925168Y705567D01*
G01X922802Y700419D02*
X925237Y704168D01*
G01X920406Y696729D02*
X921305Y698113D01*
G01X934956Y711204D02*
X948369D01*
G01X935433Y710054D02*
X948370D01*
G01X931019Y707267D02*
X934956Y711204D01*
G01X931496Y706117D02*
X935433Y710054D01*
G01X927374Y707267D02*
X931019D01*
G01X927766Y706117D02*
X931496D01*
G01X925168Y705567D02*
X927374Y707267D01*
G01X925237Y704168D02*
X927766Y706117D01*
G01X924379Y704959D02*
X925168Y705567D01*
G01X925237Y704168D02*
X927766Y706117D01*
G01X922802Y700419D02*
X925237Y704168D01*
G01X920406Y696729D02*
X921305Y698113D01*
G01X958653Y114386D02*
X964312Y120045D01*
G01X958176Y115536D02*
X963420Y120780D01*
G01X952854Y114386D02*
X958653D01*
G01X952377Y115536D02*
X958176D01*
G01X948917Y110449D02*
X952854Y114386D01*
G01X948440Y111599D02*
X952377Y115536D01*
G01X958176D02*
X963420Y120780D01*
G01X958653Y114386D02*
X964312Y120045D01*
G01X952377Y115536D02*
X958176D01*
G01X952854Y114386D02*
X958653D01*
G01X948440Y111599D02*
X952377Y115536D01*
G01X948917Y110449D02*
X952854Y114386D01*
G01X960396Y106512D02*
X970998Y117114D01*
G01X959919Y107662D02*
X970106Y117849D01*
G01X952854Y106512D02*
X960396D01*
G01X952377Y107662D02*
X959919D01*
G01X948917Y102575D02*
X952854Y106512D01*
G01X948440Y103725D02*
X952377Y107662D01*
G01X959919D02*
X970106Y117849D01*
G01X960396Y106512D02*
X970998Y117114D01*
G01X952377Y107662D02*
X959919D01*
G01X952854Y106512D02*
X960396D01*
G01X948440Y103725D02*
X952377Y107662D01*
G01X948917Y102575D02*
X952854Y106512D01*
G01X978222Y140671D02*
X994697Y225455D01*
G01X977137Y141120D02*
X993525Y225455D01*
G01X964312Y120045D02*
X978222Y140671D01*
G01X963420Y120780D02*
X977137Y141120D01*
G01D02*
X993525Y225455D01*
G01X978222Y140671D02*
X994697Y225455D01*
G01X963420Y120780D02*
X977137Y141120D01*
G01X964312Y120045D02*
X978222Y140671D01*
G01X983520Y135684D02*
X1001003Y225663D01*
G01X982435Y136133D02*
X999831Y225663D01*
G01X970998Y117114D02*
X983520Y135684D01*
G01X970106Y117849D02*
X982435Y136133D01*
G01D02*
X999831Y225663D01*
G01X983520Y135684D02*
X1001003Y225663D01*
G01X970106Y117849D02*
X982435Y136133D01*
G01X970998Y117114D02*
X983520Y135684D01*
G01X949978Y157027D02*
X950224Y156535D01*
G01X950932Y157691D02*
X951253Y157049D01*
G01X948370Y157693D02*
G02X949978Y157027I0J-2274D01*
G01X948369Y158843D02*
G02X950932Y157691I1J-3424D01*
G01D02*
X951253Y157049D01*
G01X949978Y157027D02*
X950224Y156535D01*
G01X948369Y158843D02*
G02X950932Y157691I1J-3424D01*
G01X948370Y157693D02*
G02X949978Y157027I0J-2274D01*
G01X965761Y141020D02*
X983127Y230397D01*
G01X964676Y141469D02*
X981955Y230397D01*
G01X961280Y134376D02*
X965761Y141020D01*
G01X960388Y135111D02*
X964676Y141469D01*
G01X957038Y130134D02*
X961280Y134376D01*
G01X956561Y131284D02*
X960388Y135111D01*
G01X952854Y130134D02*
X957038D01*
G01X952377Y131284D02*
X956561D01*
G01X948917Y126197D02*
X952854Y130134D01*
G01X948440Y127347D02*
X952377Y131284D01*
G01X964676Y141469D02*
X981955Y230397D01*
G01X965761Y141020D02*
X983127Y230397D01*
G01X960388Y135111D02*
X964676Y141469D01*
G01X961280Y134376D02*
X965761Y141020D01*
G01X956561Y131284D02*
X960388Y135111D01*
G01X957038Y130134D02*
X961280Y134376D01*
G01X952377Y131284D02*
X956561D01*
G01X952854Y130134D02*
X957038D01*
G01X948440Y127347D02*
X952377Y131284D01*
G01X948917Y126197D02*
X952854Y130134D01*
G01X972053Y141136D02*
X988468Y225637D01*
G01X970968Y141582D02*
X987296Y225637D01*
G01X964131Y129254D02*
X972053Y141136D01*
G01X963237Y129987D02*
X970968Y141582D01*
G01X957137Y122260D02*
X964131Y129254D01*
G01X956660Y123410D02*
X963237Y129987D01*
G01X952854Y122260D02*
X957137D01*
G01X952377Y123410D02*
X956660D01*
G01X948917Y118323D02*
X952854Y122260D01*
G01X948440Y119473D02*
X952377Y123410D01*
G01X970968Y141582D02*
X987296Y225637D01*
G01X972053Y141136D02*
X988468Y225637D01*
G01X963237Y129987D02*
X970968Y141582D01*
G01X964131Y129254D02*
X972053Y141136D01*
G01X956660Y123410D02*
X963237Y129987D01*
G01X957137Y122260D02*
X964131Y129254D01*
G01X952377Y123410D02*
X956660D01*
G01X952854Y122260D02*
X957137D01*
G01X948440Y119473D02*
X952377Y123410D01*
G01X948917Y118323D02*
X952854Y122260D01*
G01X949978Y204271D02*
X950224Y203779D01*
G01X950932Y204935D02*
X951253Y204293D01*
G01X948370Y204937D02*
G02X949978Y204271I0J-2274D01*
G01X948369Y206087D02*
G02X950932Y204935I1J-3424D01*
G01D02*
X951253Y204293D01*
G01X949978Y204271D02*
X950224Y203779D01*
G01X948369Y206087D02*
G02X950932Y204935I1J-3424D01*
G01X948370Y204937D02*
G02X949978Y204271I0J-2274D01*
G01Y188523D02*
X950224Y188031D01*
G01X950932Y189187D02*
X951253Y188545D01*
G01X948370Y189189D02*
G02X949978Y188523I0J-2274D01*
G01X948369Y190339D02*
G02X950932Y189187I1J-3424D01*
G01D02*
X951253Y188545D01*
G01X949978Y188523D02*
X950224Y188031D01*
G01X948369Y190339D02*
G02X950932Y189187I1J-3424D01*
G01X948370Y189189D02*
G02X949978Y188523I0J-2274D01*
G01Y172775D02*
X950224Y172283D01*
G01X950932Y173439D02*
X951253Y172797D01*
G01X948370Y173441D02*
G02X949978Y172775I0J-2274D01*
G01X948369Y174591D02*
G02X950932Y173439I1J-3424D01*
G01D02*
X951253Y172797D01*
G01X949978Y172775D02*
X950224Y172283D01*
G01X948369Y174591D02*
G02X950932Y173439I1J-3424D01*
G01X948370Y173441D02*
G02X949978Y172775I0J-2274D01*
G01X994697Y225455D02*
X972336Y340521D01*
G01X993525Y225455D02*
X971251Y340072D01*
G01X993525Y225455D02*
X971251Y340072D01*
G01X994697Y225455D02*
X972336Y340521D01*
G01X983127Y230397D02*
X962148Y338367D01*
G01X981955Y230397D02*
X961068Y337895D01*
G01X981955Y230397D02*
X961068Y337895D01*
G01X983127Y230397D02*
X962148Y338367D01*
G01X988470Y225637D02*
X965942Y341536D01*
G01X987298Y225637D02*
X964857Y341085D01*
G01X987298Y225637D02*
X964857Y341085D01*
G01X988470Y225637D02*
X965942Y341536D01*
G01X949978Y251515D02*
X950224Y251023D01*
G01X950932Y252179D02*
X951253Y251537D01*
G01X948370Y252181D02*
G02X949978Y251515I0J-2274D01*
G01X948369Y253331D02*
G02X950932Y252179I1J-3424D01*
G01D02*
X951253Y251537D01*
G01X949978Y251515D02*
X950224Y251023D01*
G01X948369Y253331D02*
G02X950932Y252179I1J-3424D01*
G01X948370Y252181D02*
G02X949978Y251515I0J-2274D01*
G01Y235767D02*
X950224Y235275D01*
G01X950932Y236431D02*
X951253Y235789D01*
G01X948370Y236433D02*
G02X949978Y235767I0J-2274D01*
G01X948369Y237583D02*
G02X950932Y236431I1J-3424D01*
G01D02*
X951253Y235789D01*
G01X949978Y235767D02*
X950224Y235275D01*
G01X948369Y237583D02*
G02X950932Y236431I1J-3424D01*
G01X948370Y236433D02*
G02X949978Y235767I0J-2274D01*
G01Y220019D02*
X950224Y219527D01*
G01X950932Y220683D02*
X951253Y220041D01*
G01X948370Y220685D02*
G02X949978Y220019I0J-2274D01*
G01X948369Y221835D02*
G02X950932Y220683I1J-3424D01*
G01D02*
X951253Y220041D01*
G01X949978Y220019D02*
X950224Y219527D01*
G01X948369Y221835D02*
G02X950932Y220683I1J-3424D01*
G01X948370Y220685D02*
G02X949978Y220019I0J-2274D01*
G01X1001003Y225663D02*
X978995Y338901D01*
G01X999831Y225663D02*
X977910Y338455D01*
G01X999831Y225663D02*
X977910Y338455D01*
G01X1001003Y225663D02*
X978995Y338901D01*
G01X949978Y298759D02*
X950224Y298267D01*
G01X950932Y299423D02*
X951253Y298781D01*
G01X948370Y299425D02*
G02X949978Y298759I0J-2274D01*
G01X948369Y300575D02*
G02X950932Y299423I1J-3424D01*
G01D02*
X951253Y298781D01*
G01X949978Y298759D02*
X950224Y298267D01*
G01X948369Y300575D02*
G02X950932Y299423I1J-3424D01*
G01X948370Y299425D02*
G02X949978Y298759I0J-2274D01*
G01Y283011D02*
X950224Y282519D01*
G01X950932Y283675D02*
X951253Y283033D01*
G01X948370Y283677D02*
G02X949978Y283011I0J-2274D01*
G01X948369Y284827D02*
G02X950932Y283675I1J-3424D01*
G01D02*
X951253Y283033D01*
G01X949978Y283011D02*
X950224Y282519D01*
G01X948369Y284827D02*
G02X950932Y283675I1J-3424D01*
G01X948370Y283677D02*
G02X949978Y283011I0J-2274D01*
G01Y267263D02*
X950224Y266771D01*
G01X950932Y267927D02*
X951253Y267285D01*
G01X948370Y267929D02*
G02X949978Y267263I0J-2274D01*
G01X948369Y269079D02*
G02X950932Y267927I1J-3424D01*
G01D02*
X951253Y267285D01*
G01X949978Y267263D02*
X950224Y266771D01*
G01X948369Y269079D02*
G02X950932Y267927I1J-3424D01*
G01X948370Y267929D02*
G02X949978Y267263I0J-2274D01*
G01X972336Y340521D02*
X962214Y355527D01*
G01X971251Y340072D02*
X961357Y354739D01*
G01X971251Y340072D02*
X961357Y354739D01*
G01X972336Y340521D02*
X962214Y355527D01*
G01X978995Y338901D02*
X964706Y360336D01*
G01X977910Y338455D02*
X963847Y359551D01*
G01X977910Y338455D02*
X963847Y359551D01*
G01X978995Y338901D02*
X964706Y360336D01*
G01X959369Y342158D02*
X954857Y348316D01*
G01X958441Y341478D02*
X954018Y347514D01*
G01X961120Y339771D02*
X959369Y342158D01*
G01X960192Y339090D02*
X958441Y341478D01*
G01X961558Y339173D02*
X961120Y339771D01*
G01X960192Y339090D02*
X958441Y341478D01*
G01X961068Y337895D02*
X960192Y339090D01*
G01X962148Y338367D02*
X961558Y339173D01*
G01X961068Y337895D02*
X960192Y339090D01*
G01X958441Y341478D02*
X954018Y347514D01*
G01X959369Y342158D02*
X954857Y348316D01*
G01X960192Y339090D02*
X958441Y341478D01*
G01X961120Y339771D02*
X959369Y342158D01*
G01X961558Y339173D02*
X961120Y339771D01*
G01X961068Y337895D02*
X960192Y339090D01*
G01X961558Y339173D02*
X961120Y339771D01*
G01X962148Y338367D02*
X961558Y339173D01*
G01X965810Y341731D02*
X959186Y351516D01*
G01X964857Y341086D02*
X958330Y350727D01*
G01X965942Y341536D02*
X965810Y341731D01*
G01X964857Y341086D02*
X958330Y350727D01*
G01X964857Y341086D02*
X958330Y350727D01*
G01X965810Y341731D02*
X959186Y351516D01*
G01X965942Y341536D02*
X965810Y341731D01*
G01X949978Y330255D02*
X950224Y329763D01*
G01X950932Y330919D02*
X951253Y330277D01*
G01X948370Y330921D02*
G02X949978Y330255I0J-2274D01*
G01X948369Y332071D02*
G02X950932Y330919I1J-3424D01*
G01D02*
X951253Y330277D01*
G01X949978Y330255D02*
X950224Y329763D01*
G01X948369Y332071D02*
G02X950932Y330919I1J-3424D01*
G01X948370Y330921D02*
G02X949978Y330255I0J-2274D01*
G01Y314507D02*
X950224Y314015D01*
G01X950932Y315171D02*
X951253Y314529D01*
G01X948370Y315173D02*
G02X949978Y314507I0J-2274D01*
G01X948369Y316323D02*
G02X950932Y315171I1J-3424D01*
G01D02*
X951253Y314529D01*
G01X949978Y314507D02*
X950224Y314015D01*
G01X948369Y316323D02*
G02X950932Y315171I1J-3424D01*
G01X948370Y315173D02*
G02X949978Y314507I0J-2274D01*
G01Y677892D02*
X950224Y677400D01*
G01X950932Y678556D02*
X951253Y677914D01*
G01X948370Y678558D02*
G02X949978Y677892I0J-2274D01*
G01X948369Y679708D02*
G02X950932Y678556I1J-3424D01*
G01D02*
X951253Y677914D01*
G01X949978Y677892D02*
X950224Y677400D01*
G01X948369Y679708D02*
G02X950932Y678556I1J-3424D01*
G01X948370Y678558D02*
G02X949978Y677892I0J-2274D01*
G01Y662144D02*
X950224Y661652D01*
G01X950932Y662808D02*
X951253Y662166D01*
G01X948370Y662810D02*
G02X949978Y662144I0J-2274D01*
G01X948369Y663960D02*
G02X950932Y662808I1J-3424D01*
G01D02*
X951253Y662166D01*
G01X949978Y662144D02*
X950224Y661652D01*
G01X948369Y663960D02*
G02X950932Y662808I1J-3424D01*
G01X948370Y662810D02*
G02X949978Y662144I0J-2274D01*
G01Y693640D02*
X950224Y693148D01*
G01X950932Y694304D02*
X951253Y693662D01*
G01X948370Y694306D02*
G02X949978Y693640I0J-2274D01*
G01X948369Y695456D02*
G02X950932Y694304I1J-3424D01*
G01D02*
X951253Y693662D01*
G01X949978Y693640D02*
X950224Y693148D01*
G01X948369Y695456D02*
G02X950932Y694304I1J-3424D01*
G01X948370Y694306D02*
G02X949978Y693640I0J-2274D01*
G01Y709388D02*
X950224Y708896D01*
G01X950932Y710052D02*
X951253Y709410D01*
G01X948370Y710054D02*
G02X949978Y709388I0J-2274D01*
G01X948369Y711204D02*
G02X950932Y710052I1J-3424D01*
G01D02*
X951253Y709410D01*
G01X949978Y709388D02*
X950224Y708896D01*
G01X948369Y711204D02*
G02X950932Y710052I1J-3424D01*
G01X948370Y710054D02*
G02X949978Y709388I0J-2274D01*
G01X1028724Y554925D02*
X1041128Y514046D01*
G01X1038506Y526649D02*
X1038985Y525070D01*
G01X1037229Y530859D02*
X1037708Y529280D01*
G01X1030623Y552629D02*
X1036430Y533491D01*
G01X1028724Y554925D02*
X1041128Y514046D01*
G01X1028724Y554925D02*
X1041128Y514046D01*
G01X1038506Y526649D02*
X1038985Y525070D01*
G01X1028724Y554925D02*
X1041128Y514046D01*
G01X1037229Y530859D02*
X1037708Y529280D01*
G01X1028724Y554925D02*
X1041128Y514046D01*
G01X1030623Y552629D02*
X1036430Y533491D01*
G01X1028724Y554925D02*
X1041128Y514046D01*
G01X1026169Y563345D02*
X1028723Y554928D01*
G01X1029346Y556839D02*
X1029825Y555261D01*
G01X1028068Y561050D02*
X1028547Y559471D01*
G01X1024891Y567556D02*
X1026164Y563360D01*
G01X1026790Y565260D02*
X1027266Y563693D01*
G01X1017008Y593536D02*
X1024890Y567559D01*
G01X1020185Y587030D02*
X1025992Y567892D01*
G01X1018907Y591241D02*
X1019387Y589662D01*
G01X1015730Y597747D02*
X1017007Y593539D01*
G01X1017630Y595451D02*
X1018109Y593872D01*
G01X1007847Y623727D02*
X1015729Y597750D01*
G01X1016352Y599662D02*
X1016831Y598083D01*
G01X1029346Y556839D02*
X1029825Y555261D01*
G01X1026169Y563345D02*
X1028723Y554928D01*
G01X1028068Y561050D02*
X1028547Y559471D01*
G01X1026169Y563345D02*
X1028723Y554928D01*
G01X1026790Y565260D02*
X1027266Y563693D01*
G01X1024891Y567556D02*
X1026164Y563360D01*
G01X1020185Y587030D02*
X1025992Y567892D01*
G01X1017008Y593536D02*
X1024890Y567559D01*
G01X1018907Y591241D02*
X1019387Y589662D01*
G01X1017008Y593536D02*
X1024890Y567559D01*
G01X1017630Y595451D02*
X1018109Y593872D01*
G01X1015730Y597747D02*
X1017007Y593539D01*
G01X1016352Y599662D02*
X1016831Y598083D01*
G01X1007847Y623727D02*
X1015729Y597750D01*
G01X1007847Y623727D02*
X1015729Y597750D01*
G01X1009747Y621432D02*
X1015554Y602293D01*
G01X1008469Y625642D02*
X1008948Y624063D01*
G01X1007192Y629853D02*
X1007671Y628274D01*
G01X1009747Y621432D02*
X1015554Y602293D01*
G01X1008469Y625642D02*
X1008948Y624063D01*
G01X1007192Y629853D02*
X1007671Y628274D01*
G01X1026453Y704011D02*
X1078040Y624573D01*
G01X1027507Y704501D02*
X1066705Y644140D01*
G01X1026453Y704011D02*
X1078040Y624573D01*
G01X1026453Y704011D02*
X1078040Y624573D01*
G01X1026453Y704011D02*
X1078040Y624573D01*
G01X1026453Y704011D02*
X1078040Y624573D01*
G01X1026453Y704011D02*
X1078040Y624573D01*
G01X1027507Y704501D02*
X1066705Y644140D01*
G01X1026453Y704011D02*
X1078040Y624573D01*
G01X1020870Y699244D02*
X1081454Y605956D01*
G01X1021924Y699734D02*
X1070119Y625523D01*
G01X1020870Y699244D02*
X1081454Y605956D01*
G01X1020870Y699244D02*
X1081454Y605956D01*
G01X1020870Y699244D02*
X1081454Y605956D01*
G01X1020870Y699244D02*
X1081454Y605956D01*
G01X1020870Y699244D02*
X1081454Y605956D01*
G01X1021924Y699734D02*
X1070119Y625523D01*
G01X1020870Y699244D02*
X1081454Y605956D01*
G01X1035763Y719135D02*
X1075084Y658592D01*
G01X1036817Y719625D02*
X1075948Y659375D01*
G01X1036817Y719625D02*
X1075948Y659375D01*
G01X1035763Y719135D02*
X1075084Y658592D01*
G01X1032683Y710343D02*
X1075423Y644528D01*
G01X1031629Y709853D02*
X1074558Y643747D01*
G01X1031629Y709853D02*
X1074558Y643747D01*
G01X1032683Y710343D02*
X1075423Y644528D01*
G01X1088942Y157091D02*
X1073699Y180116D01*
G01X1074775Y180576D02*
X1089766Y157930D01*
G01X1074775Y180576D02*
X1089766Y157930D01*
G01X1088942Y157091D02*
X1073699Y180116D01*
G01X1084156Y196480D02*
X1065989Y276748D01*
G01X1085232Y196939D02*
X1071053Y259585D01*
G01X1089453Y188475D02*
X1084156Y196480D01*
G01X1090283Y189305D02*
X1085232Y196939D01*
G01X1084156Y196480D02*
X1065989Y276748D01*
G01X1084156Y196480D02*
X1065989Y276748D01*
G01X1084156Y196480D02*
X1065989Y276748D01*
G01X1084156Y196480D02*
X1065989Y276748D01*
G01X1085232Y196939D02*
X1071053Y259585D01*
G01X1084156Y196480D02*
X1065989Y276748D01*
G01X1090283Y189305D02*
X1085232Y196939D01*
G01X1089453Y188475D02*
X1084156Y196480D01*
G01X1079481Y187990D02*
X1058564Y280428D01*
G01X1080557Y188450D02*
X1063627Y263265D01*
G01X1089742Y172491D02*
X1079481Y187990D01*
G01X1090566Y173330D02*
X1080557Y188450D01*
G01X1079481Y187990D02*
X1058564Y280428D01*
G01X1079481Y187990D02*
X1058564Y280428D01*
G01X1079481Y187990D02*
X1058564Y280428D01*
G01X1079481Y187990D02*
X1058564Y280428D01*
G01X1080557Y188450D02*
X1063627Y263265D01*
G01X1079481Y187990D02*
X1058564Y280428D01*
G01X1090566Y173330D02*
X1080557Y188450D01*
G01X1089742Y172491D02*
X1079481Y187990D01*
G01X1073699Y180116D02*
X1050492Y282695D01*
G01X1055555Y265532D02*
X1074775Y180576D01*
G01X1055555Y265532D02*
X1074775Y180576D01*
G01X1073699Y180116D02*
X1050492Y282695D01*
G01X1073699Y180116D02*
X1050492Y282695D01*
G01X1073699Y180116D02*
X1050492Y282695D01*
G01X1073699Y180116D02*
X1050492Y282695D01*
G01X1073699Y180116D02*
X1050492Y282695D01*
G01X1089893Y205771D02*
X1073594Y277792D01*
G01X1090969Y206231D02*
X1078658Y260629D01*
G01X1089893Y205771D02*
X1073594Y277792D01*
G01X1089893Y205771D02*
X1073594Y277792D01*
G01X1089893Y205771D02*
X1073594Y277792D01*
G01X1089893Y205771D02*
X1073594Y277792D01*
G01X1090969Y206231D02*
X1078658Y260629D01*
G01X1089893Y205771D02*
X1073594Y277792D01*
G01D02*
X1087243Y339399D01*
G01X1074773Y277795D02*
X1084444Y321446D01*
G01X1075137Y276186D02*
X1074773Y277795D01*
G01X1076108Y271894D02*
X1075744Y273504D01*
G01X1077080Y267603D02*
X1076715Y269212D01*
G01X1078051Y263311D02*
X1077687Y264921D01*
G01X1073594Y277792D02*
X1087243Y339399D01*
G01X1073594Y277792D02*
X1087243Y339399D01*
G01X1073594Y277792D02*
X1087243Y339399D01*
G01X1073594Y277792D02*
X1087243Y339399D01*
G01X1074773Y277795D02*
X1084444Y321446D01*
G01X1073594Y277792D02*
X1087243Y339399D01*
G01X1075137Y276186D02*
X1074773Y277795D01*
G01X1076108Y271894D02*
X1075744Y273504D01*
G01X1077080Y267603D02*
X1076715Y269212D01*
G01X1078051Y263311D02*
X1077687Y264921D01*
G01X1065989Y276748D02*
X1080798Y343618D01*
G01X1067168Y276751D02*
X1078001Y325665D01*
G01X1067532Y275142D02*
X1067168Y276751D01*
G01X1068503Y270854D02*
X1068139Y272460D01*
G01X1069475Y266559D02*
X1069111Y268168D01*
G01X1070446Y262267D02*
X1070084Y263869D01*
G01X1065989Y276748D02*
X1080798Y343618D01*
G01X1065989Y276748D02*
X1080798Y343618D01*
G01X1065989Y276748D02*
X1080798Y343618D01*
G01X1065989Y276748D02*
X1080798Y343618D01*
G01X1067168Y276751D02*
X1078001Y325665D01*
G01X1065989Y276748D02*
X1080798Y343618D01*
G01X1067532Y275142D02*
X1067168Y276751D01*
G01X1068503Y270854D02*
X1068139Y272460D01*
G01X1069475Y266559D02*
X1069111Y268168D01*
G01X1070446Y262267D02*
X1070084Y263869D01*
G01X1058564Y280428D02*
X1072765Y344503D01*
G01X1059743Y280431D02*
X1069965Y326551D01*
G01X1060107Y278822D02*
X1059743Y280431D01*
G01X1061078Y274530D02*
X1060714Y276139D01*
G01X1062049Y270239D02*
X1061685Y271848D01*
G01X1063020Y265947D02*
X1062656Y267556D01*
G01X1058564Y280428D02*
X1072765Y344503D01*
G01X1058564Y280428D02*
X1072765Y344503D01*
G01X1058564Y280428D02*
X1072765Y344503D01*
G01X1058564Y280428D02*
X1072765Y344503D01*
G01X1059743Y280431D02*
X1069965Y326551D01*
G01X1058564Y280428D02*
X1072765Y344503D01*
G01X1060107Y278822D02*
X1059743Y280431D01*
G01X1061078Y274530D02*
X1060714Y276139D01*
G01X1062049Y270239D02*
X1061685Y271848D01*
G01X1063020Y265947D02*
X1062656Y267556D01*
G01X1050492Y282695D02*
X1063717Y342385D01*
G01X1060918Y324432D02*
X1051671Y282698D01*
G01X1054584Y269823D02*
X1054948Y268214D01*
G01X1053613Y274115D02*
X1053977Y272506D01*
G01X1052642Y278406D02*
X1053006Y276797D01*
G01X1051671Y282698D02*
X1052035Y281089D01*
G01X1054584Y269823D02*
X1054948Y268214D01*
G01X1053613Y274115D02*
X1053977Y272506D01*
G01X1052642Y278406D02*
X1053006Y276797D01*
G01X1051671Y282698D02*
X1052035Y281089D01*
G01X1060918Y324432D02*
X1051671Y282698D01*
G01X1050492Y282695D02*
X1063717Y342385D01*
G01X1050492Y282695D02*
X1063717Y342385D01*
G01X1050492Y282695D02*
X1063717Y342385D01*
G01X1050492Y282695D02*
X1063717Y342385D01*
G01X1050492Y282695D02*
X1063717Y342385D01*
G01X1087243Y339399D02*
X1093593Y348994D01*
G01X1086994Y332957D02*
X1087351Y334568D01*
G01X1086025Y328583D02*
X1086382Y330194D01*
G01X1085056Y324209D02*
X1085413Y325820D01*
G01X1087243Y339399D02*
X1093593Y348994D01*
G01X1086994Y332957D02*
X1087351Y334568D01*
G01X1086025Y328583D02*
X1086382Y330194D01*
G01X1085056Y324209D02*
X1085413Y325820D01*
G01X1086892Y352842D02*
X1101651Y362614D01*
G01X1087723Y352012D02*
X1102108Y361537D01*
G01X1080798Y343618D02*
X1086892Y352842D01*
G01X1081876Y343161D02*
X1087723Y352012D01*
G01X1081519Y341550D02*
X1081876Y343161D01*
G01X1080550Y337176D02*
X1080907Y338787D01*
G01X1079582Y332802D02*
X1079939Y334413D01*
G01X1078613Y328428D02*
X1078970Y330039D01*
G01X1087723Y352012D02*
X1102108Y361537D01*
G01X1086892Y352842D02*
X1101651Y362614D01*
G01X1081876Y343161D02*
X1087723Y352012D01*
G01X1080798Y343618D02*
X1086892Y352842D01*
G01X1081519Y341550D02*
X1081876Y343161D01*
G01X1080550Y337176D02*
X1080907Y338787D01*
G01X1079582Y332802D02*
X1079939Y334413D01*
G01X1078613Y328428D02*
X1078970Y330039D01*
G01X1082504Y357133D02*
X1098329Y367610D01*
G01X1072765Y344503D02*
X1081674Y357963D01*
G01X1073842Y344046D02*
X1082504Y357133D01*
G01X1073485Y342435D02*
X1073842Y344046D01*
G01X1072516Y338061D02*
X1072873Y339672D01*
G01X1071546Y333687D02*
X1071903Y335298D01*
G01X1070577Y329313D02*
X1070934Y330924D01*
G01X1082504Y357133D02*
X1098329Y367610D01*
G01X1073842Y344046D02*
X1082504Y357133D01*
G01X1072765Y344503D02*
X1081674Y357963D01*
G01X1073485Y342435D02*
X1073842Y344046D01*
G01X1072516Y338061D02*
X1072873Y339672D01*
G01X1071546Y333687D02*
X1071903Y335298D01*
G01X1070577Y329313D02*
X1070934Y330924D01*
G01X1063717Y342385D02*
X1077845Y363732D01*
G01X1078675Y362902D02*
X1064794Y341928D01*
G01X1061887Y328806D02*
X1061530Y327195D01*
G01X1062856Y333180D02*
X1062499Y331569D01*
G01X1063825Y337554D02*
X1063468Y335943D01*
G01X1064794Y341928D02*
X1064437Y340317D01*
G01X1061887Y328806D02*
X1061530Y327195D01*
G01X1062856Y333180D02*
X1062499Y331569D01*
G01X1063825Y337554D02*
X1063468Y335943D01*
G01X1064794Y341928D02*
X1064437Y340317D01*
G01X1078675Y362902D02*
X1064794Y341928D01*
G01X1063717Y342385D02*
X1077845Y363732D01*
G01X1081674Y357963D02*
X1097872Y368688D01*
G01X1081674Y357963D02*
X1097872Y368688D01*
G01X1077845Y363732D02*
X1093400Y374028D01*
G01X1093857Y372951D02*
X1078675Y362902D01*
G01X1093857Y372951D02*
X1078675Y362902D01*
G01X1077845Y363732D02*
X1093400Y374028D01*
G01X1069597Y482109D02*
X1091842Y447856D01*
G01X1069597Y482109D02*
X1091842Y447856D01*
G01X1069597Y482109D02*
X1091842Y447856D01*
G01X1069597Y482109D02*
X1091842Y447856D01*
G01X1069597Y482109D02*
X1091842Y447856D01*
G01X1069597Y482109D02*
X1091842Y447856D01*
G01X1082710Y451944D02*
X1092570Y437218D01*
G01X1069525Y473704D02*
X1093464Y437952D01*
G01X1053900Y494971D02*
X1082710Y451944D01*
G01X1069525Y473704D02*
X1093464Y437952D01*
G01X1082710Y451944D02*
X1092570Y437218D01*
G01X1053900Y494971D02*
X1082710Y451944D01*
G01X1053900Y494971D02*
X1082710Y451944D01*
G01X1062783Y532352D02*
X1091351Y488364D01*
G01X1085763Y499081D02*
X1086662Y497697D01*
G01X1083367Y502771D02*
X1084265Y501388D01*
G01X1062783Y532352D02*
X1091351Y488364D01*
G01X1062783Y532352D02*
X1091351Y488364D01*
G01X1085763Y499081D02*
X1086662Y497697D01*
G01X1062783Y532352D02*
X1091351Y488364D01*
G01X1083367Y502771D02*
X1084265Y501388D01*
G01X1062783Y532352D02*
X1091351Y488364D01*
G01X1062783Y532352D02*
X1091351Y488364D01*
G01X1062783Y532352D02*
X1091351Y488364D01*
G01X1086689Y457903D02*
X1087588Y456519D01*
G01X1084293Y461593D02*
X1085192Y460209D01*
G01X1071902Y480672D02*
X1082795Y463899D01*
G01X1047396Y516292D02*
X1069597Y482109D01*
G01X1069505Y484362D02*
X1070404Y482978D01*
G01X1067109Y488052D02*
X1068007Y486669D01*
G01X1064712Y491742D02*
X1065611Y490359D01*
G01X1048450Y516782D02*
X1063214Y494049D01*
G01X1086689Y457903D02*
X1087588Y456519D01*
G01X1084293Y461593D02*
X1085192Y460209D01*
G01X1071902Y480672D02*
X1082795Y463899D01*
G01X1069505Y484362D02*
X1070404Y482978D01*
G01X1047396Y516292D02*
X1069597Y482109D01*
G01X1067109Y488052D02*
X1068007Y486669D01*
G01X1047396Y516292D02*
X1069597Y482109D01*
G01X1064712Y491742D02*
X1065611Y490359D01*
G01X1047396Y516292D02*
X1069597Y482109D01*
G01X1048450Y516782D02*
X1063214Y494049D01*
G01X1047396Y516292D02*
X1069597Y482109D01*
G01X1045594Y544348D02*
X1092657Y471878D01*
G01X1087529Y481888D02*
X1093489Y472710D01*
G01X1085133Y485578D02*
X1086031Y484194D01*
G01X1082736Y489268D02*
X1083635Y487884D01*
G01X1080340Y492958D02*
X1081238Y491574D01*
G01X1077943Y496648D02*
X1078842Y495264D01*
G01X1046648Y544838D02*
X1076446Y498955D01*
G01X1087529Y481888D02*
X1093489Y472710D01*
G01X1045594Y544348D02*
X1092657Y471878D01*
G01X1085133Y485578D02*
X1086031Y484194D01*
G01X1045594Y544348D02*
X1092657Y471878D01*
G01X1082736Y489268D02*
X1083635Y487884D01*
G01X1045594Y544348D02*
X1092657Y471878D01*
G01X1080340Y492958D02*
X1081238Y491574D01*
G01X1045594Y544348D02*
X1092657Y471878D01*
G01X1077943Y496648D02*
X1078842Y495264D01*
G01X1045594Y544348D02*
X1092657Y471878D01*
G01X1046648Y544838D02*
X1076446Y498955D01*
G01X1045594Y544348D02*
X1092657Y471878D01*
G01X1067077Y477360D02*
X1067995Y475989D01*
G01X1064629Y481016D02*
X1065547Y479645D01*
G01X1041128Y514046D02*
X1053900Y494971D01*
G01X1049523Y503576D02*
X1050441Y502205D01*
G01X1067077Y477360D02*
X1067995Y475989D01*
G01X1064629Y481016D02*
X1065547Y479645D01*
G01X1049523Y503576D02*
X1050441Y502205D01*
G01X1041128Y514046D02*
X1053900Y494971D01*
G01X1041128Y514046D02*
X1053900Y494971D01*
G01X1041128Y514046D02*
X1053900Y494971D01*
G01X1041128Y514046D02*
X1053900Y494971D01*
G01X1056980Y557586D02*
X1091899Y503821D01*
G01X1085730Y515432D02*
X1086629Y514048D01*
G01X1083334Y519122D02*
X1084233Y517738D01*
G01X1080937Y522812D02*
X1081836Y521428D01*
G01X1058034Y558076D02*
X1079439Y525118D01*
G01X1056980Y557586D02*
X1091899Y503821D01*
G01X1056980Y557586D02*
X1091899Y503821D01*
G01X1085730Y515432D02*
X1086629Y514048D01*
G01X1056980Y557586D02*
X1091899Y503821D01*
G01X1083334Y519122D02*
X1084233Y517738D01*
G01X1056980Y557586D02*
X1091899Y503821D01*
G01X1080937Y522812D02*
X1081836Y521428D01*
G01X1056980Y557586D02*
X1091899Y503821D01*
G01X1058034Y558076D02*
X1079439Y525118D01*
G01X1056980Y557586D02*
X1091899Y503821D01*
G01X1080970Y506461D02*
X1081869Y505078D01*
G01X1054271Y547573D02*
X1079472Y508768D01*
G01X1053217Y547083D02*
X1062784Y532352D01*
G01X1054271Y547573D02*
X1079472Y508768D01*
G01X1080970Y506461D02*
X1081869Y505078D01*
G01X1054271Y547573D02*
X1079472Y508768D01*
G01X1053217Y547083D02*
X1062784Y532352D01*
G01X1046871Y518022D02*
X1047396Y516292D01*
G01X1047973Y518355D02*
X1048450Y516782D01*
G01X1044794Y524867D02*
X1046870Y518025D01*
G01X1046693Y522571D02*
X1047172Y520992D01*
G01X1045416Y526782D02*
X1045895Y525203D01*
G01X1047973Y518355D02*
X1048450Y516782D01*
G01X1046871Y518022D02*
X1047396Y516292D01*
G01X1046693Y522571D02*
X1047172Y520992D01*
G01X1044794Y524867D02*
X1046870Y518025D01*
G01X1045416Y526782D02*
X1045895Y525203D01*
G01X1047075Y507232D02*
X1047993Y505861D01*
G01X1044627Y510888D02*
X1045545Y509517D01*
G01X1042179Y514544D02*
X1043097Y513173D01*
G01X1041061Y518228D02*
X1042179Y514544D01*
G01X1039784Y522438D02*
X1040263Y520859D01*
G01X1047075Y507232D02*
X1047993Y505861D01*
G01X1044627Y510888D02*
X1045545Y509517D01*
G01X1042179Y514544D02*
X1043097Y513173D01*
G01X1041061Y518228D02*
X1042179Y514544D01*
G01X1039784Y522438D02*
X1040263Y520859D01*
G01X1074552Y643740D02*
X1094905Y627377D01*
G01X1074552Y643740D02*
X1094905Y627377D01*
G01X1074552Y643740D02*
X1094905Y627377D01*
G01X1074552Y643740D02*
X1094905Y627377D01*
G01X1087041Y635175D02*
X1088327Y634141D01*
G01X1074552Y643740D02*
X1094905Y627377D01*
G01X1084836Y636949D02*
X1085665Y637039D01*
G01X1074552Y643740D02*
X1094905Y627377D01*
G01X1083550Y637983D02*
X1084836Y636949D01*
G01X1074552Y643740D02*
X1094905Y627377D01*
G01X1081344Y639756D02*
X1082174Y639846D01*
G01X1074552Y643740D02*
X1094905Y627377D01*
G01X1080059Y640790D02*
X1081344Y639756D01*
G01X1074552Y643740D02*
X1094905Y627377D01*
G01X1077853Y642563D02*
X1078683Y642653D01*
G01X1074552Y643740D02*
X1094905Y627377D01*
G01X1075418Y644521D02*
X1077853Y642563D01*
G01X1074552Y643740D02*
X1094905Y627377D01*
G01X1074552Y643740D02*
X1094905Y627377D01*
G01X1087041Y635175D02*
X1088327Y634141D01*
G01X1084836Y636949D02*
X1085665Y637039D01*
G01X1083550Y637983D02*
X1084836Y636949D01*
G01X1081344Y639756D02*
X1082174Y639846D01*
G01X1080059Y640790D02*
X1081344Y639756D01*
G01X1077853Y642563D02*
X1078683Y642653D01*
G01X1075418Y644521D02*
X1077853Y642563D01*
G01X1078040Y624573D02*
X1094128Y611629D01*
G01X1078905Y625354D02*
X1094534Y612779D01*
G01X1078006Y626738D02*
X1078905Y625354D01*
G01X1075566Y630495D02*
X1076465Y629111D01*
G01X1073126Y634252D02*
X1074025Y632868D01*
G01X1070686Y638010D02*
X1071585Y636626D01*
G01X1068246Y641767D02*
X1069145Y640383D01*
G01X1078905Y625354D02*
X1094534Y612779D01*
G01X1078040Y624573D02*
X1094128Y611629D01*
G01X1078006Y626738D02*
X1078905Y625354D01*
G01X1075566Y630495D02*
X1076465Y629111D01*
G01X1073126Y634252D02*
X1074025Y632868D01*
G01X1070686Y638010D02*
X1071585Y636626D01*
G01X1068246Y641767D02*
X1069145Y640383D01*
G01X1081454Y605956D02*
X1093972Y595881D01*
G01X1082319Y606737D02*
X1094378Y597031D01*
G01X1081420Y608121D02*
X1082319Y606737D01*
G01X1078980Y611878D02*
X1079879Y610494D01*
G01X1076540Y615635D02*
X1077439Y614251D01*
G01X1074100Y619392D02*
X1074999Y618009D01*
G01X1071660Y623150D02*
X1072559Y621766D01*
G01X1082319Y606737D02*
X1094378Y597031D01*
G01X1081454Y605956D02*
X1093972Y595881D01*
G01X1081420Y608121D02*
X1082319Y606737D01*
G01X1078980Y611878D02*
X1079879Y610494D01*
G01X1076540Y615635D02*
X1077439Y614251D01*
G01X1074100Y619392D02*
X1074999Y618009D01*
G01X1071660Y623150D02*
X1072559Y621766D01*
G01X1082001Y691041D02*
X1090250Y678328D01*
G01X1083082Y691488D02*
X1091082Y679160D01*
G01X1076917Y714954D02*
X1082001Y691041D01*
G01X1078099Y714925D02*
X1083082Y691488D01*
G01D02*
X1091082Y679160D01*
G01X1082001Y691041D02*
X1090250Y678328D01*
G01X1078099Y714925D02*
X1083082Y691488D01*
G01X1076917Y714954D02*
X1082001Y691041D01*
G01X1075712Y686996D02*
X1092482Y661181D01*
G01X1076784Y687458D02*
X1093314Y662013D01*
G01X1070038Y713665D02*
X1075703Y687009D01*
G01X1071220Y713636D02*
X1076784Y687458D01*
G01D02*
X1093314Y662013D01*
G01X1075712Y686996D02*
X1092482Y661181D01*
G01X1071220Y713636D02*
X1076784Y687458D01*
G01X1070038Y713665D02*
X1075703Y687009D01*
G01X1075086Y658594D02*
X1094326Y643125D01*
G01X1087748Y649889D02*
X1088578Y649980D01*
G01X1086462Y650923D02*
X1087748Y649889D01*
G01X1084257Y652697D02*
X1085086Y652787D01*
G01X1082971Y653731D02*
X1084257Y652697D01*
G01X1080765Y655504D02*
X1081595Y655594D01*
G01X1079480Y656538D02*
X1080765Y655504D01*
G01X1077274Y658311D02*
X1078104Y658401D01*
G01X1075950Y659376D02*
X1077274Y658311D01*
G01X1075086Y658594D02*
X1094326Y643125D01*
G01X1075086Y658594D02*
X1094326Y643125D01*
G01X1075086Y658594D02*
X1094326Y643125D01*
G01X1087748Y649889D02*
X1088578Y649980D01*
G01X1075086Y658594D02*
X1094326Y643125D01*
G01X1086462Y650923D02*
X1087748Y649889D01*
G01X1075086Y658594D02*
X1094326Y643125D01*
G01X1084257Y652697D02*
X1085086Y652787D01*
G01X1075086Y658594D02*
X1094326Y643125D01*
G01X1082971Y653731D02*
X1084257Y652697D01*
G01X1075086Y658594D02*
X1094326Y643125D01*
G01X1080765Y655504D02*
X1081595Y655594D01*
G01X1075086Y658594D02*
X1094326Y643125D01*
G01X1079480Y656538D02*
X1080765Y655504D01*
G01X1075086Y658594D02*
X1094326Y643125D01*
G01X1077274Y658311D02*
X1078104Y658401D01*
G01X1075086Y658594D02*
X1094326Y643125D01*
G01X1075950Y659376D02*
X1077274Y658311D01*
G01X1075086Y658594D02*
X1094326Y643125D01*
G01X1086921Y700593D02*
X1092267Y692356D01*
G01X1083880Y714897D02*
X1086921Y700593D01*
G01X1085062Y714868D02*
X1088002Y701040D01*
G01X1087578Y728910D02*
X1083880Y714897D01*
G01X1088594Y728250D02*
X1085063Y714868D01*
G01X1098900Y738019D02*
X1087578Y728910D01*
G01X1086921Y700593D02*
X1092267Y692356D01*
G01X1085062Y714868D02*
X1088002Y701040D01*
G01X1083880Y714897D02*
X1086921Y700593D01*
G01X1088594Y728250D02*
X1085063Y714868D01*
G01X1087578Y728910D02*
X1083880Y714897D01*
G01X1098900Y738019D02*
X1087578Y728910D01*
G01X1081242Y731358D02*
X1076917Y714954D01*
G01X1082258Y730699D02*
X1078099Y714925D01*
G01X1096789Y743868D02*
X1081242Y731358D01*
G01X1097343Y742837D02*
X1082258Y730699D01*
G01D02*
X1078099Y714925D01*
G01X1081242Y731358D02*
X1076917Y714954D01*
G01X1097343Y742837D02*
X1082258Y730699D01*
G01X1096789Y743868D02*
X1081242Y731358D01*
G01X1075351Y733800D02*
X1070038Y713665D01*
G01X1076367Y733139D02*
X1071220Y713636D01*
G01X1095026Y749623D02*
X1075352Y733800D01*
G01X1095580Y748592D02*
X1076368Y733140D01*
G01X1076367Y733139D02*
X1071220Y713636D01*
G01X1075351Y733800D02*
X1070038Y713665D01*
G01X1095580Y748592D02*
X1076368Y733140D01*
G01X1095026Y749623D02*
X1075352Y733800D01*
G01X1094177Y153756D02*
X1088942Y157091D01*
G01X1089766Y157930D02*
X1094513Y154906D01*
G01X1099985Y153756D02*
X1094177D01*
G01X1094513Y154906D02*
X1099508D01*
G01X1103922Y157693D02*
X1099985Y153756D01*
G01X1099508Y154906D02*
X1103445Y158843D01*
G01X1116480Y157693D02*
X1103922D01*
G01X1103445Y158843D02*
X1116479D01*
G01X1118088Y157027D02*
G03X1116480Y157693I-1608J-1608D01*
G01X1116479Y158843D02*
G02X1119042Y157691I1J-3424D01*
G01X1118334Y156535D02*
X1118088Y157027D01*
G01X1119042Y157691D02*
X1119363Y157049D01*
G01X1119042Y157691D02*
X1119363Y157049D01*
G01X1118334Y156535D02*
X1118088Y157027D01*
G01X1116479Y158843D02*
G02X1119042Y157691I1J-3424D01*
G01X1118088Y157027D02*
G03X1116480Y157693I-1608J-1608D01*
G01X1103445Y158843D02*
X1116479D01*
G01X1116480Y157693D02*
X1103922D01*
G01X1099508Y154906D02*
X1103445Y158843D01*
G01X1103922Y157693D02*
X1099985Y153756D01*
G01X1094513Y154906D02*
X1099508D01*
G01X1099985Y153756D02*
X1094177D01*
G01X1089766Y157930D02*
X1094513Y154906D01*
G01X1094177Y153756D02*
X1088942Y157091D01*
G01X1136752Y211673D02*
X1124463Y217898D01*
G01X1146535Y205428D02*
X1124188Y216748D01*
G01X1146535Y205428D02*
X1124188Y216748D01*
G01X1146535Y205428D02*
X1124188Y216748D01*
G01X1146535Y205428D02*
X1124188Y216748D01*
G01X1136752Y211673D02*
X1124463Y217898D01*
G01X1091581Y203223D02*
X1089893Y205771D01*
G01X1092411Y204053D02*
X1090969Y206231D01*
G01X1094940Y201000D02*
X1091581Y203223D01*
G01X1095287Y202150D02*
X1092411Y204053D01*
G01X1099727Y201000D02*
X1094940D01*
G01X1099250Y202150D02*
X1095287D01*
G01X1103664Y204937D02*
X1099727Y201000D01*
G01X1103187Y206087D02*
X1099250Y202150D01*
G01X1116480Y204937D02*
X1103664D01*
G01X1116479Y206087D02*
X1103187D01*
G01X1118088Y204271D02*
G03X1116480Y204937I-1608J-1608D01*
G01X1119042Y204935D02*
G03X1116479Y206087I-2562J-2272D01*
G01X1118334Y203779D02*
X1118088Y204271D01*
G01X1119363Y204293D02*
X1119042Y204935D01*
G01X1092411Y204053D02*
X1090969Y206231D01*
G01X1091581Y203223D02*
X1089893Y205771D01*
G01X1095287Y202150D02*
X1092411Y204053D01*
G01X1094940Y201000D02*
X1091581Y203223D01*
G01X1099250Y202150D02*
X1095287D01*
G01X1099727Y201000D02*
X1094940D01*
G01X1103187Y206087D02*
X1099250Y202150D01*
G01X1103664Y204937D02*
X1099727Y201000D01*
G01X1116479Y206087D02*
X1103187D01*
G01X1116480Y204937D02*
X1103664D01*
G01X1119042Y204935D02*
G03X1116479Y206087I-2562J-2272D01*
G01X1118088Y204271D02*
G03X1116480Y204937I-1608J-1608D01*
G01X1119363Y204293D02*
X1119042Y204935D01*
G01X1118334Y203779D02*
X1118088Y204271D01*
G01X1093816Y185584D02*
X1089453Y188475D01*
G01X1094265Y186667D02*
X1090283Y189305D01*
G01X1095450Y185252D02*
X1093816Y185584D01*
G01X1095566Y186402D02*
X1094265Y186667D01*
G01X1099779Y185252D02*
X1095450D01*
G01X1099302Y186402D02*
X1095566D01*
G01X1103716Y189189D02*
X1099779Y185252D01*
G01X1103239Y190339D02*
X1099302Y186402D01*
G01X1116480Y189189D02*
X1103716D01*
G01X1116479Y190339D02*
X1103239D01*
G01X1118088Y188523D02*
G03X1116480Y189189I-1608J-1608D01*
G01X1119042Y189187D02*
G03X1116479Y190339I-2562J-2272D01*
G01X1118334Y188031D02*
X1118088Y188523D01*
G01X1119363Y188545D02*
X1119042Y189187D01*
G01X1094265Y186667D02*
X1090283Y189305D01*
G01X1093816Y185584D02*
X1089453Y188475D01*
G01X1095566Y186402D02*
X1094265Y186667D01*
G01X1095450Y185252D02*
X1093816Y185584D01*
G01X1099302Y186402D02*
X1095566D01*
G01X1099779Y185252D02*
X1095450D01*
G01X1103239Y190339D02*
X1099302Y186402D01*
G01X1103716Y189189D02*
X1099779Y185252D01*
G01X1116479Y190339D02*
X1103239D01*
G01X1116480Y189189D02*
X1103716D01*
G01X1119042Y189187D02*
G03X1116479Y190339I-2562J-2272D01*
G01X1118088Y188523D02*
G03X1116480Y189189I-1608J-1608D01*
G01X1119363Y188545D02*
X1119042Y189187D01*
G01X1118334Y188031D02*
X1118088Y188523D01*
G01X1094431Y169504D02*
X1089742Y172491D01*
G01X1094767Y170654D02*
X1090566Y173330D01*
G01X1099731Y169504D02*
X1094431D01*
G01X1099254Y170654D02*
X1094767D01*
G01X1103668Y173441D02*
X1099731Y169504D01*
G01X1103191Y174591D02*
X1099254Y170654D01*
G01X1116480Y173441D02*
X1103668D01*
G01X1116479Y174591D02*
X1103191D01*
G01X1118088Y172775D02*
G03X1116480Y173441I-1608J-1608D01*
G01X1119042Y173439D02*
G03X1116479Y174591I-2562J-2272D01*
G01X1118334Y172283D02*
X1118088Y172775D01*
G01X1119363Y172797D02*
X1119042Y173439D01*
G01X1094767Y170654D02*
X1090566Y173330D01*
G01X1094431Y169504D02*
X1089742Y172491D01*
G01X1099254Y170654D02*
X1094767D01*
G01X1099731Y169504D02*
X1094431D01*
G01X1103191Y174591D02*
X1099254Y170654D01*
G01X1103668Y173441D02*
X1099731Y169504D01*
G01X1116479Y174591D02*
X1103191D01*
G01X1116480Y173441D02*
X1103668D01*
G01X1119042Y173439D02*
G03X1116479Y174591I-2562J-2272D01*
G01X1118088Y172775D02*
G03X1116480Y173441I-1608J-1608D01*
G01X1119363Y172797D02*
X1119042Y173439D01*
G01X1118334Y172283D02*
X1118088Y172775D01*
G01X1337404Y155590D02*
X1128512Y261400D01*
G01X1133758Y260032D02*
X1129091Y262396D01*
G01X1137612Y258080D02*
X1136140Y258825D01*
G01X1133758Y260032D02*
X1129091Y262396D01*
G01X1337404Y155590D02*
X1128512Y261400D01*
G01X1137612Y258080D02*
X1136140Y258825D01*
G01X1337404Y155590D02*
X1128512Y261400D01*
G01X1337404Y155590D02*
X1128512Y261400D01*
G01X1337404Y155590D02*
X1128512Y261400D01*
G01X1119146Y249396D02*
X1118825Y250038D01*
G01X1120100Y250060D02*
X1119854Y250552D01*
G01X1121709Y248244D02*
G02X1119146Y249396I-1J3424D01*
G01X1121708Y249394D02*
G02X1120100Y250060I0J2274D01*
G01X1124097Y248244D02*
X1121709D01*
G01X1124213Y249394D02*
X1121708D01*
G01X1128960Y247254D02*
X1124097Y248244D01*
G01X1129409Y248337D02*
X1124213Y249394D01*
G01X1189984Y206862D02*
X1128960Y247254D01*
G01X1137332Y243092D02*
X1129409Y248337D01*
G01X1120100Y250060D02*
X1119854Y250552D01*
G01X1119146Y249396D02*
X1118825Y250038D01*
G01X1121708Y249394D02*
G02X1120100Y250060I0J2274D01*
G01X1121709Y248244D02*
G02X1119146Y249396I-1J3424D01*
G01X1124213Y249394D02*
X1121708D01*
G01X1124097Y248244D02*
X1121709D01*
G01X1129409Y248337D02*
X1124213Y249394D01*
G01X1128960Y247254D02*
X1124097Y248244D01*
G01X1137332Y243092D02*
X1129409Y248337D01*
G01X1189984Y206862D02*
X1128960Y247254D01*
G01X1189984Y206862D02*
X1128960Y247254D01*
G01X1189984Y206862D02*
X1128960Y247254D01*
G01X1189984Y206862D02*
X1128960Y247254D01*
G01X1119146Y233648D02*
X1118825Y234290D01*
G01X1120100Y234312D02*
X1119854Y234804D01*
G01X1121708Y232496D02*
G02X1119146Y233648I0J3424D01*
G01X1121708Y233646D02*
G02X1120100Y234312I0J2274D01*
G01X1123513Y232496D02*
X1121708D01*
G01X1123629Y233646D02*
X1121708D01*
G01X1129204Y231341D02*
X1123513Y232496D01*
G01X1129652Y232424D02*
X1123629Y233646D01*
G01X1159900Y211035D02*
X1129204Y231341D01*
G01X1141609Y224514D02*
X1129652Y232424D01*
G01X1120100Y234312D02*
X1119854Y234804D01*
G01X1119146Y233648D02*
X1118825Y234290D01*
G01X1121708Y233646D02*
G02X1120100Y234312I0J2274D01*
G01X1121708Y232496D02*
G02X1119146Y233648I0J3424D01*
G01X1123629Y233646D02*
X1121708D01*
G01X1123513Y232496D02*
X1121708D01*
G01X1129652Y232424D02*
X1123629Y233646D01*
G01X1129204Y231341D02*
X1123513Y232496D01*
G01X1141609Y224514D02*
X1129652Y232424D01*
G01X1159900Y211035D02*
X1129204Y231341D01*
G01X1159900Y211035D02*
X1129204Y231341D01*
G01X1159900Y211035D02*
X1129204Y231341D01*
G01X1159900Y211035D02*
X1129204Y231341D01*
G01X1120100Y218564D02*
X1119854Y219056D01*
G01X1119146Y217900D02*
X1118825Y218542D01*
G01X1121708Y217898D02*
G02X1120100Y218564I0J2274D01*
G01X1121709Y216748D02*
G02X1119146Y217900I-1J3424D01*
G01X1124463Y217898D02*
X1121708D01*
G01X1124188Y216748D02*
X1121709D01*
G01X1119146Y217900D02*
X1118825Y218542D01*
G01X1120100Y218564D02*
X1119854Y219056D01*
G01X1121709Y216748D02*
G02X1119146Y217900I-1J3424D01*
G01X1121708Y217898D02*
G02X1120100Y218564I0J2274D01*
G01X1124188Y216748D02*
X1121709D01*
G01X1124463Y217898D02*
X1121708D01*
G01X1127626Y294789D02*
X1174789Y263572D01*
G01X1128075Y295872D02*
X1138853Y288738D01*
G01X1124190Y295488D02*
X1127626Y294789D01*
G01X1124306Y296638D02*
X1128075Y295872D01*
G01X1121709Y295488D02*
X1124190D01*
G01X1121708Y296638D02*
X1124306D01*
G01X1119146Y296640D02*
G03X1121709Y295488I2562J2272D01*
G01X1120100Y297304D02*
G03X1121708Y296638I1608J1608D01*
G01X1118825Y297282D02*
X1119146Y296640D01*
G01X1119854Y297796D02*
X1120100Y297304D01*
G01X1127626Y294789D02*
X1174789Y263572D01*
G01X1127626Y294789D02*
X1174789Y263572D01*
G01X1127626Y294789D02*
X1174789Y263572D01*
G01X1128075Y295872D02*
X1138853Y288738D01*
G01X1127626Y294789D02*
X1174789Y263572D01*
G01X1124306Y296638D02*
X1128075Y295872D01*
G01X1124190Y295488D02*
X1127626Y294789D01*
G01X1121708Y296638D02*
X1124306D01*
G01X1121709Y295488D02*
X1124190D01*
G01X1120100Y297304D02*
G03X1121708Y296638I1608J1608D01*
G01X1119146Y296640D02*
G03X1121709Y295488I2562J2272D01*
G01X1119854Y297796D02*
X1120100Y297304D01*
G01X1118825Y297282D02*
X1119146Y296640D01*
G01X1128015Y279228D02*
X1199367Y232002D01*
G01X1128464Y280311D02*
X1134317Y276437D01*
G01X1125507Y279740D02*
X1128015Y279228D01*
G01X1125623Y280890D02*
X1128464Y280311D01*
G01X1121709Y279740D02*
X1125507D01*
G01X1121708Y280890D02*
X1125623D01*
G01X1119146Y280892D02*
G03X1121709Y279740I2562J2272D01*
G01X1120100Y281556D02*
G03X1121708Y280890I1608J1608D01*
G01X1118825Y281534D02*
X1119146Y280892D01*
G01X1119854Y282048D02*
X1120100Y281556D01*
G01X1128015Y279228D02*
X1199367Y232002D01*
G01X1128015Y279228D02*
X1199367Y232002D01*
G01X1128015Y279228D02*
X1199367Y232002D01*
G01X1128464Y280311D02*
X1134317Y276437D01*
G01X1128015Y279228D02*
X1199367Y232002D01*
G01X1125623Y280890D02*
X1128464Y280311D01*
G01X1125507Y279740D02*
X1128015Y279228D01*
G01X1121708Y280890D02*
X1125623D01*
G01X1121709Y279740D02*
X1125507D01*
G01X1120100Y281556D02*
G03X1121708Y280890I1608J1608D01*
G01X1119146Y280892D02*
G03X1121709Y279740I2562J2272D01*
G01X1119854Y282048D02*
X1120100Y281556D01*
G01X1118825Y281534D02*
X1119146Y280892D01*
G01Y265144D02*
X1118825Y265786D01*
G01X1120100Y265808D02*
X1119854Y266300D01*
G01X1121709Y263992D02*
G02X1119146Y265144I-1J3424D01*
G01X1121708Y265142D02*
G02X1120100Y265808I0J2274D01*
G01X1124597Y263992D02*
X1121709D01*
G01X1124944Y265142D02*
X1121708D01*
G01X1128512Y261400D02*
X1124597Y263992D01*
G01X1129091Y262396D02*
X1124944Y265142D01*
G01X1120100Y265808D02*
X1119854Y266300D01*
G01X1119146Y265144D02*
X1118825Y265786D01*
G01X1121708Y265142D02*
G02X1120100Y265808I0J2274D01*
G01X1121709Y263992D02*
G02X1119146Y265144I-1J3424D01*
G01X1124944Y265142D02*
X1121708D01*
G01X1124597Y263992D02*
X1121709D01*
G01X1129091Y262396D02*
X1124944Y265142D01*
G01X1128512Y261400D02*
X1124597Y263992D01*
G01X1127509Y326984D02*
X1235086Y306072D01*
G01X1127620Y328134D02*
X1177096Y318517D01*
G01X1121709Y326984D02*
X1127509D01*
G01X1121708Y328134D02*
X1127620D01*
G01X1119146Y328136D02*
G03X1121709Y326984I2562J2272D01*
G01X1120100Y328800D02*
G03X1121708Y328134I1608J1608D01*
G01X1118825Y328778D02*
X1119146Y328136D01*
G01X1119854Y329292D02*
X1120100Y328800D01*
G01X1127509Y326984D02*
X1235086Y306072D01*
G01X1127509Y326984D02*
X1235086Y306072D01*
G01X1127509Y326984D02*
X1235086Y306072D01*
G01X1127620Y328134D02*
X1177096Y318517D01*
G01X1127509Y326984D02*
X1235086Y306072D01*
G01X1121708Y328134D02*
X1127620D01*
G01X1121709Y326984D02*
X1127509D01*
G01X1120100Y328800D02*
G03X1121708Y328134I1608J1608D01*
G01X1119146Y328136D02*
G03X1121709Y326984I2562J2272D01*
G01X1119854Y329292D02*
X1120100Y328800D01*
G01X1118825Y328778D02*
X1119146Y328136D01*
G01X1126371Y311236D02*
X1246035Y287976D01*
G01X1126482Y312386D02*
X1176336Y302696D01*
G01X1121706Y311236D02*
X1126371D01*
G01X1121707Y312386D02*
X1126482D01*
G01X1119147Y312388D02*
G03X1121706Y311236I2561J2272D01*
G01X1120101Y313052D02*
G03X1121707Y312386I1608J1608D01*
G01X1118825Y313030D02*
X1119147Y312388D01*
G01X1119854Y313544D02*
X1120101Y313052D01*
G01X1126371Y311236D02*
X1246035Y287976D01*
G01X1126371Y311236D02*
X1246035Y287976D01*
G01X1126371Y311236D02*
X1246035Y287976D01*
G01X1126482Y312386D02*
X1176336Y302696D01*
G01X1126371Y311236D02*
X1246035Y287976D01*
G01X1121707Y312386D02*
X1126482D01*
G01X1121706Y311236D02*
X1126371D01*
G01X1120101Y313052D02*
G03X1121707Y312386I1608J1608D01*
G01X1119147Y312388D02*
G03X1121706Y311236I2561J2272D01*
G01X1119854Y313544D02*
X1120101Y313052D01*
G01X1118825Y313030D02*
X1119147Y312388D01*
G01X1115928Y358690D02*
X1202193Y339699D01*
G01X1133117Y353728D02*
X1160178Y347770D01*
G01X1128820Y354674D02*
X1130432Y354319D01*
G01X1124523Y355620D02*
X1126135Y355265D01*
G01X1115929Y357512D02*
X1121838Y356211D01*
G01X1104374Y356129D02*
X1115928Y358690D01*
G01X1104831Y355052D02*
X1115929Y357512D01*
G01X1093593Y348994D02*
X1104374Y356129D01*
G01X1094423Y348164D02*
X1104831Y355052D01*
G01X1088320Y338942D02*
X1094423Y348164D01*
G01X1087963Y337331D02*
X1088320Y338942D01*
G01X1115928Y358690D02*
X1202193Y339699D01*
G01X1115928Y358690D02*
X1202193Y339699D01*
G01X1133117Y353728D02*
X1160178Y347770D01*
G01X1115928Y358690D02*
X1202193Y339699D01*
G01X1128820Y354674D02*
X1130432Y354319D01*
G01X1115928Y358690D02*
X1202193Y339699D01*
G01X1124523Y355620D02*
X1126135Y355265D01*
G01X1115928Y358690D02*
X1202193Y339699D01*
G01X1115929Y357512D02*
X1121838Y356211D01*
G01X1115928Y358690D02*
X1202193Y339699D01*
G01X1104831Y355052D02*
X1115929Y357512D01*
G01X1104374Y356129D02*
X1115928Y358690D01*
G01X1094423Y348164D02*
X1104831Y355052D01*
G01X1093593Y348994D02*
X1104374Y356129D01*
G01X1088320Y338942D02*
X1094423Y348164D01*
G01X1087963Y337331D02*
X1088320Y338942D01*
G01X1114442Y365449D02*
X1200872Y346399D01*
G01X1131075Y360605D02*
X1163119Y353542D01*
G01X1126778Y361552D02*
X1128390Y361197D01*
G01X1122481Y362499D02*
X1124093Y362144D01*
G01X1114443Y364271D02*
X1119796Y363091D01*
G01X1101651Y362614D02*
X1114442Y365449D01*
G01X1102108Y361537D02*
X1114443Y364271D01*
G01X1114442Y365449D02*
X1200872Y346399D01*
G01X1114442Y365449D02*
X1200872Y346399D01*
G01X1131075Y360605D02*
X1163119Y353542D01*
G01X1114442Y365449D02*
X1200872Y346399D01*
G01X1126778Y361552D02*
X1128390Y361197D01*
G01X1114442Y365449D02*
X1200872Y346399D01*
G01X1122481Y362499D02*
X1124093Y362144D01*
G01X1114442Y365449D02*
X1200872Y346399D01*
G01X1114443Y364271D02*
X1119796Y363091D01*
G01X1114442Y365449D02*
X1200872Y346399D01*
G01X1102108Y361537D02*
X1114443Y364271D01*
G01X1101651Y362614D02*
X1114442Y365449D01*
G01X1115164Y372521D02*
X1231936Y346815D01*
G01X1129633Y368158D02*
X1163242Y360759D01*
G01X1125336Y369104D02*
X1126947Y368749D01*
G01X1121039Y370050D02*
X1122650Y369695D01*
G01X1115165Y371343D02*
X1118353Y370641D01*
G01X1097872Y368688D02*
X1115164Y372521D01*
G01X1098329Y367611D02*
X1115165Y371343D01*
G01X1115164Y372521D02*
X1231936Y346815D01*
G01X1115164Y372521D02*
X1231936Y346815D01*
G01X1129633Y368158D02*
X1163242Y360759D01*
G01X1115164Y372521D02*
X1231936Y346815D01*
G01X1125336Y369104D02*
X1126947Y368749D01*
G01X1115164Y372521D02*
X1231936Y346815D01*
G01X1121039Y370050D02*
X1122650Y369695D01*
G01X1115164Y372521D02*
X1231936Y346815D01*
G01X1115165Y371343D02*
X1118353Y370641D01*
G01X1115164Y372521D02*
X1231936Y346815D01*
G01X1098329Y367611D02*
X1115165Y371343D01*
G01X1097872Y368688D02*
X1115164Y372521D01*
G01X1115971Y379032D02*
X1237166Y352446D01*
G01X1119050Y377179D02*
X1115972Y377854D01*
G01X1123347Y376236D02*
X1121736Y376590D01*
G01X1127645Y375293D02*
X1126034Y375647D01*
G01X1162992Y367539D02*
X1130331Y374704D01*
G01X1093400Y374028D02*
X1115971Y379032D01*
G01X1115972Y377854D02*
X1093857Y372951D01*
G01X1115972Y377854D02*
X1093857Y372951D01*
G01X1093400Y374028D02*
X1115971Y379032D01*
G01X1119050Y377179D02*
X1115972Y377854D01*
G01X1115971Y379032D02*
X1237166Y352446D01*
G01X1123347Y376236D02*
X1121736Y376590D01*
G01X1115971Y379032D02*
X1237166Y352446D01*
G01X1127645Y375293D02*
X1126034Y375647D01*
G01X1115971Y379032D02*
X1237166Y352446D01*
G01X1162992Y367539D02*
X1130331Y374704D01*
G01X1115971Y379032D02*
X1237166Y352446D01*
G01X1115971Y379032D02*
X1237166Y352446D01*
G01X1115971Y379032D02*
X1237166Y352446D01*
G01X1101401Y447576D02*
X1101647Y448069D01*
G01X1100461Y448271D02*
X1100618Y448583D01*
G01X1098320Y446300D02*
G03X1101401Y447576I0J4357D01*
G01X1098321Y447450D02*
G03X1100461Y448271I-3J3206D01*
G01X1095338Y446300D02*
X1098320D01*
G01X1095459Y447450D02*
X1098321D01*
G01X1093707Y446646D02*
X1095338Y446300D01*
G01X1094154Y447727D02*
X1095459Y447450D01*
G01X1091842Y447856D02*
X1093707Y446646D01*
G01X1092674Y448688D02*
X1094154Y447727D01*
G01X1091482Y450523D02*
X1092674Y448688D01*
G01X1089086Y454213D02*
X1089985Y452829D01*
G01X1100461Y448271D02*
X1100618Y448583D01*
G01X1101401Y447576D02*
X1101647Y448069D01*
G01X1098321Y447450D02*
G03X1100461Y448271I-3J3206D01*
G01X1098320Y446300D02*
G03X1101401Y447576I0J4357D01*
G01X1095459Y447450D02*
X1098321D01*
G01X1095338Y446300D02*
X1098320D01*
G01X1094154Y447727D02*
X1095459Y447450D01*
G01X1093707Y446646D02*
X1095338Y446300D01*
G01X1092674Y448688D02*
X1094154Y447727D01*
G01X1091842Y447856D02*
X1093707Y446646D01*
G01X1091482Y450523D02*
X1092674Y448688D01*
G01X1089086Y454213D02*
X1089985Y452829D01*
G01X1128736Y418614D02*
Y460691D01*
G01X1127586Y419091D02*
Y460214D01*
G01X1124901Y414779D02*
X1128736Y418614D01*
G01X1124424Y415929D02*
X1127586Y419091D01*
G01X1120907Y414779D02*
X1124901D01*
G01X1121384Y415929D02*
X1124424D01*
G01X1116970Y418716D02*
X1120907Y414779D01*
G01X1117447Y419866D02*
X1121384Y415929D01*
G01X1103445Y418716D02*
X1116970D01*
G01X1103922Y419866D02*
X1117447D01*
G01X1100803Y421358D02*
X1103445Y418716D01*
G01X1101953Y421835D02*
X1103922Y419866D01*
G01X1100803Y428986D02*
Y421358D01*
G01X1101953Y429463D02*
Y421835D01*
G01X1092570Y437218D02*
X1100803Y428986D01*
G01X1093464Y437952D02*
X1101953Y429463D01*
G01X1127586Y419091D02*
Y460214D01*
G01X1128736Y418614D02*
Y460691D01*
G01X1124424Y415929D02*
X1127586Y419091D01*
G01X1124901Y414779D02*
X1128736Y418614D01*
G01X1121384Y415929D02*
X1124424D01*
G01X1120907Y414779D02*
X1124901D01*
G01X1117447Y419866D02*
X1121384Y415929D01*
G01X1116970Y418716D02*
X1120907Y414779D01*
G01X1103922Y419866D02*
X1117447D01*
G01X1103445Y418716D02*
X1116970D01*
G01X1101953Y421835D02*
X1103922Y419866D01*
G01X1100803Y421358D02*
X1103445Y418716D01*
G01X1101953Y429463D02*
Y421835D01*
G01X1100803Y428986D02*
Y421358D01*
G01X1093464Y437952D02*
X1101953Y429463D01*
G01X1092570Y437218D02*
X1100803Y428986D01*
G01X1099985Y501393D02*
X1103922Y505330D01*
G01X1099508Y502543D02*
X1103445Y506480D01*
G01X1095638Y501393D02*
X1099985D01*
G01X1095979Y502543D02*
X1099508D01*
G01X1091899Y503821D02*
X1095638Y501393D01*
G01X1092731Y504653D02*
X1095979Y502543D01*
G01X1099508D02*
X1103445Y506480D01*
G01X1099985Y501393D02*
X1103922Y505330D01*
G01X1095979Y502543D02*
X1099508D01*
G01X1095638Y501393D02*
X1099985D01*
G01X1092731Y504653D02*
X1095979Y502543D01*
G01X1091899Y503821D02*
X1095638Y501393D01*
G01X1118088Y488916D02*
X1118334Y488424D01*
G01X1119042Y489580D02*
X1119363Y488938D01*
G01X1116480Y489582D02*
G02X1118088Y488916I0J-2274D01*
G01X1116479Y490732D02*
G02X1119042Y489580I1J-3424D01*
G01X1103873Y489582D02*
X1116480D01*
G01X1103396Y490732D02*
X1116479D01*
G01X1099936Y485645D02*
X1103873Y489582D01*
G01X1099459Y486795D02*
X1103396Y490732D01*
G01X1095540Y485645D02*
X1099936D01*
G01X1095881Y486795D02*
X1099459D01*
G01X1091351Y488364D02*
X1095540Y485645D01*
G01X1092183Y489196D02*
X1095881Y486795D01*
G01X1090556Y491701D02*
X1092183Y489196D01*
G01X1088160Y495391D02*
X1089058Y494007D01*
G01X1119042Y489580D02*
X1119363Y488938D01*
G01X1118088Y488916D02*
X1118334Y488424D01*
G01X1116479Y490732D02*
G02X1119042Y489580I1J-3424D01*
G01X1116480Y489582D02*
G02X1118088Y488916I0J-2274D01*
G01X1103396Y490732D02*
X1116479D01*
G01X1103873Y489582D02*
X1116480D01*
G01X1099459Y486795D02*
X1103396Y490732D01*
G01X1099936Y485645D02*
X1103873Y489582D01*
G01X1095881Y486795D02*
X1099459D01*
G01X1095540Y485645D02*
X1099936D01*
G01X1092183Y489196D02*
X1095881Y486795D01*
G01X1091351Y488364D02*
X1095540Y485645D01*
G01X1090556Y491701D02*
X1092183Y489196D01*
G01X1088160Y495391D02*
X1089058Y494007D01*
G01X1118088Y473168D02*
X1118334Y472676D01*
G01X1119042Y473832D02*
X1119363Y473190D01*
G01X1116480Y473834D02*
G02X1118088Y473168I0J-2274D01*
G01X1116479Y474984D02*
G02X1119042Y473832I1J-3424D01*
G01X1103922Y473834D02*
X1116480D01*
G01X1103445Y474984D02*
X1116479D01*
G01X1099985Y469897D02*
X1103922Y473834D01*
G01X1099508Y471047D02*
X1103445Y474984D01*
G01X1095707Y469897D02*
X1099985D01*
G01X1096048Y471047D02*
X1099508D01*
G01X1092657Y471878D02*
X1095707Y469897D01*
G01X1093489Y472710D02*
X1096048Y471047D01*
G01X1119042Y473832D02*
X1119363Y473190D01*
G01X1118088Y473168D02*
X1118334Y472676D01*
G01X1116479Y474984D02*
G02X1119042Y473832I1J-3424D01*
G01X1116480Y473834D02*
G02X1118088Y473168I0J-2274D01*
G01X1103445Y474984D02*
X1116479D01*
G01X1103922Y473834D02*
X1116480D01*
G01X1099508Y471047D02*
X1103445Y474984D01*
G01X1099985Y469897D02*
X1103922Y473834D01*
G01X1096048Y471047D02*
X1099508D01*
G01X1095707Y469897D02*
X1099985D01*
G01X1093489Y472710D02*
X1096048Y471047D01*
G01X1092657Y471878D02*
X1095707Y469897D01*
G01X1118159Y457275D02*
X1118333Y456927D01*
G01X1119116Y457933D02*
X1119362Y457441D01*
G01X1118301Y460929D02*
G03X1118159Y457275I1904J-1904D01*
G01X1119033Y458022D02*
G03X1119115Y457934I1169J1007D01*
G01Y460115D02*
G03X1119033Y458022I1090J-1091D01*
G01X1119032Y461660D02*
X1118301Y460929D01*
G01X1121023Y462023D02*
X1119115Y460115D01*
G01X1120546Y463173D02*
X1119033Y461660D01*
G01X1121023Y462023D02*
X1119115Y460115D01*
G01X1126254Y463173D02*
X1120546D01*
G01X1125777Y462023D02*
X1121023D01*
G01X1128736Y460691D02*
X1126254Y463173D01*
G01X1127586Y460214D02*
X1125777Y462023D01*
G01X1119116Y457933D02*
X1119362Y457441D01*
G01X1118159Y457275D02*
X1118333Y456927D01*
G01X1119033Y458022D02*
G03X1119115Y457934I1169J1007D01*
G01X1118301Y460929D02*
G03X1118159Y457275I1904J-1904D01*
G01X1119115Y460115D02*
G03X1119033Y458022I1090J-1091D01*
G01X1118301Y460929D02*
G03X1118159Y457275I1904J-1904D01*
G01X1121023Y462023D02*
X1119115Y460115D01*
G01X1119032Y461660D02*
X1118301Y460929D01*
G01X1120546Y463173D02*
X1119033Y461660D01*
G01X1125777Y462023D02*
X1121023D01*
G01X1126254Y463173D02*
X1120546D01*
G01X1127586Y460214D02*
X1125777Y462023D01*
G01X1128736Y460691D02*
X1126254Y463173D01*
G01X1118088Y504664D02*
X1118334Y504172D01*
G01X1119042Y505328D02*
X1119363Y504686D01*
G01X1116480Y505330D02*
G02X1118088Y504664I0J-2274D01*
G01X1116479Y506480D02*
G02X1119042Y505328I1J-3424D01*
G01X1103922Y505330D02*
X1116480D01*
G01X1103445Y506480D02*
X1116479D01*
G01X1090524Y508052D02*
X1092731Y504653D01*
G01X1088127Y511742D02*
X1089026Y510358D01*
G01X1119042Y505328D02*
X1119363Y504686D01*
G01X1118088Y504664D02*
X1118334Y504172D01*
G01X1116479Y506480D02*
G02X1119042Y505328I1J-3424D01*
G01X1116480Y505330D02*
G02X1118088Y504664I0J-2274D01*
G01X1103445Y506480D02*
X1116479D01*
G01X1103922Y505330D02*
X1116480D01*
G01X1090524Y508052D02*
X1092731Y504653D01*
G01X1088127Y511742D02*
X1089026Y510358D01*
G01X1118088Y599152D02*
X1118334Y598660D01*
G01X1119042Y599816D02*
X1119363Y599174D01*
G01X1116480Y599818D02*
G02X1118088Y599152I0J-2274D01*
G01X1099762Y595881D02*
X1103699Y599818D01*
G01X1099285Y597031D02*
X1103222Y600968D01*
G01X1093972Y595881D02*
X1099762D01*
G01X1094378Y597031D02*
X1099285D01*
G01X1119042Y599816D02*
X1119363Y599174D01*
G01X1118088Y599152D02*
X1118334Y598660D01*
G01X1116480Y599818D02*
G02X1118088Y599152I0J-2274D01*
G01X1099285Y597031D02*
X1103222Y600968D01*
G01X1099762Y595881D02*
X1103699Y599818D01*
G01X1094378Y597031D02*
X1099285D01*
G01X1093972Y595881D02*
X1099762D01*
G01X1118088Y646396D02*
X1118334Y645904D01*
G01X1119042Y647060D02*
X1119363Y646418D01*
G01X1116480Y647062D02*
G02X1118088Y646396I0J-2274D01*
G01X1116479Y648212D02*
G02X1119042Y647060I1J-3424D01*
G01X1103922Y647062D02*
X1116480D01*
G01X1099985Y643125D02*
X1103922Y647062D01*
G01X1099508Y644275D02*
X1103445Y648212D01*
G01X1094326Y643125D02*
X1099985D01*
G01X1094731Y644275D02*
X1099508D01*
G01X1093445Y645309D02*
X1094731Y644275D01*
G01X1091240Y647082D02*
X1092069Y647172D01*
G01X1089954Y648116D02*
X1091240Y647082D01*
G01X1119042Y647060D02*
X1119363Y646418D01*
G01X1118088Y646396D02*
X1118334Y645904D01*
G01X1116479Y648212D02*
G02X1119042Y647060I1J-3424D01*
G01X1116480Y647062D02*
G02X1118088Y646396I0J-2274D01*
G01X1103922Y647062D02*
X1116480D01*
G01X1099508Y644275D02*
X1103445Y648212D01*
G01X1099985Y643125D02*
X1103922Y647062D01*
G01X1094731Y644275D02*
X1099508D01*
G01X1094326Y643125D02*
X1099985D01*
G01X1093445Y645309D02*
X1094731Y644275D01*
G01X1091240Y647082D02*
X1092069Y647172D01*
G01X1089954Y648116D02*
X1091240Y647082D01*
G01X1119042Y631312D02*
X1119363Y630670D01*
G01X1118088Y630648D02*
X1118334Y630156D01*
G01X1116479Y632464D02*
G02X1119042Y631312I1J-3424D01*
G01X1116480Y631314D02*
G02X1118088Y630648I0J-2274D01*
G01X1102864Y632464D02*
X1116479D01*
G01X1103341Y631314D02*
X1116480D01*
G01X1098927Y628527D02*
X1102864Y632464D01*
G01X1099404Y627377D02*
X1103341Y631314D01*
G01X1095310Y628527D02*
X1098927D01*
G01X1094905Y627377D02*
X1099404D01*
G01X1094024Y629561D02*
X1095310Y628527D01*
G01X1091819Y631334D02*
X1092648Y631424D01*
G01X1090533Y632368D02*
X1091819Y631334D01*
G01X1088327Y634141D02*
X1089157Y634232D01*
G01X1118088Y630648D02*
X1118334Y630156D01*
G01X1119042Y631312D02*
X1119363Y630670D01*
G01X1116480Y631314D02*
G02X1118088Y630648I0J-2274D01*
G01X1116479Y632464D02*
G02X1119042Y631312I1J-3424D01*
G01X1103341Y631314D02*
X1116480D01*
G01X1102864Y632464D02*
X1116479D01*
G01X1099404Y627377D02*
X1103341Y631314D01*
G01X1098927Y628527D02*
X1102864Y632464D01*
G01X1094905Y627377D02*
X1099404D01*
G01X1095310Y628527D02*
X1098927D01*
G01X1094024Y629561D02*
X1095310Y628527D01*
G01X1091819Y631334D02*
X1092648Y631424D01*
G01X1090533Y632368D02*
X1091819Y631334D01*
G01X1088327Y634141D02*
X1089157Y634232D01*
G01X1118088Y614900D02*
X1118334Y614408D01*
G01X1119042Y615564D02*
X1119363Y614922D01*
G01X1116480Y615566D02*
G02X1118088Y614900I0J-2274D01*
G01X1116479Y616716D02*
G02X1119042Y615564I1J-3424D01*
G01X1103885Y615566D02*
X1116480D01*
G01X1103408Y616716D02*
X1116479D01*
G01X1099948Y611629D02*
X1103885Y615566D01*
G01X1099471Y612779D02*
X1103408Y616716D01*
G01X1094128Y611629D02*
X1099948D01*
G01X1094534Y612779D02*
X1099471D01*
G01X1119042Y615564D02*
X1119363Y614922D01*
G01X1118088Y614900D02*
X1118334Y614408D01*
G01X1116479Y616716D02*
G02X1119042Y615564I1J-3424D01*
G01X1116480Y615566D02*
G02X1118088Y614900I0J-2274D01*
G01X1103408Y616716D02*
X1116479D01*
G01X1103885Y615566D02*
X1116480D01*
G01X1099471Y612779D02*
X1103408Y616716D01*
G01X1099948Y611629D02*
X1103885Y615566D01*
G01X1094534Y612779D02*
X1099471D01*
G01X1094128Y611629D02*
X1099948D01*
G01X1116479Y600968D02*
G02X1119042Y599816I1J-3424D01*
G01X1103699Y599818D02*
X1116480D01*
G01X1103222Y600968D02*
X1116479D01*
G01D02*
G02X1119042Y599816I1J-3424D01*
G01X1103222Y600968D02*
X1116479D01*
G01X1103699Y599818D02*
X1116480D01*
G01X1118088Y693640D02*
X1118334Y693148D01*
G01X1119042Y694304D02*
X1119363Y693662D01*
G01X1116480Y694306D02*
G02X1118088Y693640I0J-2274D01*
G01X1116479Y695456D02*
G02X1119042Y694304I1J-3424D01*
G01X1103406Y694306D02*
X1116480D01*
G01X1102929Y695456D02*
X1116479D01*
G01X1099469Y690369D02*
X1103406Y694306D01*
G01X1098992Y691519D02*
X1102929Y695456D01*
G01X1095330Y690369D02*
X1099469D01*
G01X1095671Y691519D02*
X1098992D01*
G01X1092267Y692356D02*
X1095330Y690369D01*
G01X1093099Y693188D02*
X1095671Y691519D01*
G01X1088002Y701040D02*
X1093099Y693188D01*
G01X1119042Y694304D02*
X1119363Y693662D01*
G01X1118088Y693640D02*
X1118334Y693148D01*
G01X1116479Y695456D02*
G02X1119042Y694304I1J-3424D01*
G01X1116480Y694306D02*
G02X1118088Y693640I0J-2274D01*
G01X1102929Y695456D02*
X1116479D01*
G01X1103406Y694306D02*
X1116480D01*
G01X1098992Y691519D02*
X1102929Y695456D01*
G01X1099469Y690369D02*
X1103406Y694306D01*
G01X1095671Y691519D02*
X1098992D01*
G01X1095330Y690369D02*
X1099469D01*
G01X1093099Y693188D02*
X1095671Y691519D01*
G01X1092267Y692356D02*
X1095330Y690369D01*
G01X1088002Y701040D02*
X1093099Y693188D01*
G01X1118088Y677892D02*
X1118334Y677400D01*
G01X1119042Y678556D02*
X1119363Y677914D01*
G01X1116480Y678558D02*
G02X1118088Y677892I0J-2274D01*
G01X1116479Y679708D02*
G02X1119042Y678556I1J-3424D01*
G01X1103758Y678558D02*
X1116480D01*
G01X1103281Y679708D02*
X1116479D01*
G01X1099821Y674621D02*
X1103758Y678558D01*
G01X1099344Y675771D02*
X1103281Y679708D01*
G01X1095958Y674621D02*
X1099821D01*
G01X1096299Y675771D02*
X1099344D01*
G01X1094770Y675393D02*
X1095958Y674621D01*
G01X1095397Y676358D02*
X1096299Y675771D01*
G01X1090250Y678328D02*
X1094770Y675393D01*
G01X1091082Y679160D02*
X1095397Y676358D01*
G01X1119042Y678556D02*
X1119363Y677914D01*
G01X1118088Y677892D02*
X1118334Y677400D01*
G01X1116479Y679708D02*
G02X1119042Y678556I1J-3424D01*
G01X1116480Y678558D02*
G02X1118088Y677892I0J-2274D01*
G01X1103281Y679708D02*
X1116479D01*
G01X1103758Y678558D02*
X1116480D01*
G01X1099344Y675771D02*
X1103281Y679708D01*
G01X1099821Y674621D02*
X1103758Y678558D01*
G01X1096299Y675771D02*
X1099344D01*
G01X1095958Y674621D02*
X1099821D01*
G01X1095397Y676358D02*
X1096299Y675771D01*
G01X1094770Y675393D02*
X1095958Y674621D01*
G01X1091082Y679160D02*
X1095397Y676358D01*
G01X1090250Y678328D02*
X1094770Y675393D01*
G01X1118088Y662144D02*
X1118334Y661652D01*
G01X1119042Y662808D02*
X1119363Y662166D01*
G01X1116480Y662810D02*
G02X1118088Y662144I0J-2274D01*
G01X1116479Y663960D02*
G02X1119042Y662808I1J-3424D01*
G01X1103637Y662810D02*
X1116480D01*
G01X1103160Y663960D02*
X1116479D01*
G01X1099700Y658873D02*
X1103637Y662810D01*
G01X1099223Y660023D02*
X1103160Y663960D01*
G01X1096035Y658873D02*
X1099700D01*
G01X1096376Y660023D02*
X1099223D01*
G01X1092482Y661181D02*
X1096035Y658873D01*
G01X1093314Y662013D02*
X1096376Y660023D01*
G01X1119042Y662808D02*
X1119363Y662166D01*
G01X1118088Y662144D02*
X1118334Y661652D01*
G01X1116479Y663960D02*
G02X1119042Y662808I1J-3424D01*
G01X1116480Y662810D02*
G02X1118088Y662144I0J-2274D01*
G01X1103160Y663960D02*
X1116479D01*
G01X1103637Y662810D02*
X1116480D01*
G01X1099223Y660023D02*
X1103160Y663960D01*
G01X1099700Y658873D02*
X1103637Y662810D01*
G01X1096376Y660023D02*
X1099223D01*
G01X1096035Y658873D02*
X1099700D01*
G01X1093314Y662013D02*
X1096376Y660023D01*
G01X1092482Y661181D02*
X1096035Y658873D01*
G01X1103445Y648212D02*
X1116479D01*
G01X1103445D02*
X1116479D01*
G01X1118088Y709388D02*
X1118334Y708896D01*
G01X1119042Y710052D02*
X1119363Y709410D01*
G01X1116480Y710054D02*
G02X1118088Y709388I0J-2274D01*
G01X1116479Y711204D02*
G02X1119042Y710052I1J-3424D01*
G01X1102911Y710054D02*
X1116480D01*
G01X1103388Y711204D02*
X1116479D01*
G01X1098973Y713992D02*
X1102911Y710054D01*
G01X1099449Y715143D02*
X1103388Y711204D01*
G01X1095726Y713992D02*
X1098973D01*
G01X1098497Y715143D02*
X1099449D01*
G01X1096056Y715142D02*
X1098496D01*
G01X1092745Y715852D02*
X1095726Y713992D01*
G01X1093664Y716635D02*
X1096056Y715142D01*
G01X1091352Y719165D02*
X1092745Y715852D01*
G01X1092564Y719250D02*
X1093664Y716635D01*
G01X1093315Y726604D02*
X1091352Y719165D01*
G01X1094331Y725944D02*
X1092564Y719250D01*
G01X1101668Y733318D02*
X1093315Y726604D01*
G01X1102222Y732287D02*
X1094331Y725944D01*
G01X1109372Y735783D02*
X1101668Y733318D01*
G01X1109372Y734575D02*
X1102222Y732287D01*
G01X1116502Y733502D02*
X1109372Y735783D01*
G01X1115948Y732471D02*
X1109372Y734575D01*
G01X1125859Y725979D02*
X1116502Y733502D01*
G01X1125007Y725188D02*
X1115948Y732471D01*
G01X1454022Y248647D02*
X1125859Y725979D01*
G01X1135531Y709880D02*
X1125007Y725188D01*
G01X1119042Y710052D02*
X1119363Y709410D01*
G01X1118088Y709388D02*
X1118334Y708896D01*
G01X1116479Y711204D02*
G02X1119042Y710052I1J-3424D01*
G01X1116480Y710054D02*
G02X1118088Y709388I0J-2274D01*
G01X1103388Y711204D02*
X1116479D01*
G01X1102911Y710054D02*
X1116480D01*
G01X1099449Y715143D02*
X1103388Y711204D01*
G01X1098973Y713992D02*
X1102911Y710054D01*
G01X1098497Y715143D02*
X1099449D01*
G01X1095726Y713992D02*
X1098973D01*
G01X1096056Y715142D02*
X1098496D01*
G01X1095726Y713992D02*
X1098973D01*
G01X1093664Y716635D02*
X1096056Y715142D01*
G01X1092745Y715852D02*
X1095726Y713992D01*
G01X1092564Y719250D02*
X1093664Y716635D01*
G01X1091352Y719165D02*
X1092745Y715852D01*
G01X1094331Y725944D02*
X1092564Y719250D01*
G01X1093315Y726604D02*
X1091352Y719165D01*
G01X1102222Y732287D02*
X1094331Y725944D01*
G01X1101668Y733318D02*
X1093315Y726604D01*
G01X1109372Y734575D02*
X1102222Y732287D01*
G01X1109372Y735783D02*
X1101668Y733318D01*
G01X1115948Y732471D02*
X1109372Y734575D01*
G01X1116502Y733502D02*
X1109372Y735783D01*
G01X1125007Y725188D02*
X1115948Y732471D01*
G01X1125859Y725979D02*
X1116502Y733502D01*
G01X1135531Y709880D02*
X1125007Y725188D01*
G01X1454022Y248647D02*
X1125859Y725979D01*
G01X1454022Y248647D02*
X1125859Y725979D01*
G01X1454022Y248647D02*
X1125859Y725979D01*
G01X1454022Y248647D02*
X1125859Y725979D01*
G01X1454022Y248647D02*
X1125859Y725979D01*
G01X1454022Y248647D02*
X1125859Y725979D01*
G01X1454022Y248647D02*
X1125859Y725979D01*
G01X1454022Y248647D02*
X1125859Y725979D01*
G01X1454022Y248647D02*
X1125859Y725979D01*
G01X1454022Y248647D02*
X1125859Y725979D01*
G01X1454022Y248647D02*
X1125859Y725979D01*
G01X1454022Y248647D02*
X1125859Y725979D01*
G01X1454022Y248647D02*
X1125859Y725979D01*
G01X1454022Y248647D02*
X1125859Y725979D01*
G01X1099455Y736988D02*
X1088594Y728250D01*
G01X1109387Y741370D02*
X1098900Y738019D01*
G01X1109387Y740162D02*
X1099455Y736988D01*
G01X1118651Y738414D02*
X1109387Y741370D01*
G01X1118097Y737383D02*
X1109387Y740162D01*
G01X1131177Y728339D02*
X1118651Y738414D01*
G01X1130325Y727548D02*
X1118097Y737383D01*
G01X1459282Y251539D02*
X1131182Y728339D01*
G01X1133618Y722763D02*
X1130325Y727548D01*
G01X1136112Y719138D02*
X1135177Y720497D01*
G01X1099455Y736988D02*
X1088594Y728250D01*
G01X1109387Y740162D02*
X1099455Y736988D01*
G01X1109387Y741370D02*
X1098900Y738019D01*
G01X1118097Y737383D02*
X1109387Y740162D01*
G01X1118651Y738414D02*
X1109387Y741370D01*
G01X1130325Y727548D02*
X1118097Y737383D01*
G01X1131177Y728339D02*
X1118651Y738414D01*
G01X1133618Y722763D02*
X1130325Y727548D01*
G01X1459282Y251539D02*
X1131182Y728339D01*
G01X1136112Y719138D02*
X1135177Y720497D01*
G01X1459282Y251539D02*
X1131182Y728339D01*
G01X1459282Y251539D02*
X1131182Y728339D01*
G01X1459282Y251539D02*
X1131182Y728339D01*
G01X1459282Y251539D02*
X1131182Y728339D01*
G01X1459282Y251539D02*
X1131182Y728339D01*
G01X1459282Y251539D02*
X1131182Y728339D01*
G01X1459282Y251539D02*
X1131182Y728339D01*
G01X1459282Y251539D02*
X1131182Y728339D01*
G01X1459282Y251539D02*
X1131182Y728339D01*
G01X1459282Y251539D02*
X1131182Y728339D01*
G01X1459282Y251539D02*
X1131182Y728339D01*
G01X1459282Y251539D02*
X1131182Y728339D01*
G01X1459282Y251539D02*
X1131182Y728339D01*
G01X1108775Y747693D02*
X1096789Y743868D01*
G01X1108775Y746485D02*
X1097343Y742837D01*
G01X1121909Y743503D02*
X1108775Y747693D01*
G01X1121345Y742475D02*
X1108775Y746485D01*
G01X1138851Y729396D02*
X1121909Y743503D01*
G01X1137994Y728613D02*
X1121345Y742475D01*
G01X1108775Y746485D02*
X1097343Y742837D01*
G01X1108775Y747693D02*
X1096789Y743868D01*
G01X1121345Y742475D02*
X1108775Y746485D01*
G01X1121909Y743503D02*
X1108775Y747693D01*
G01X1137994Y728613D02*
X1121345Y742475D01*
G01X1138851Y729396D02*
X1121909Y743503D01*
G01X1148567Y729623D02*
X1126082Y748347D01*
G01X1147709Y728840D02*
X1125518Y747319D01*
G01X1147709Y728840D02*
X1125518Y747319D01*
G01X1148567Y729623D02*
X1126082Y748347D01*
G01X1108541Y753940D02*
X1095026Y749623D01*
G01X1108541Y752732D02*
X1095580Y748592D01*
G01X1126082Y748347D02*
X1108541Y753940D01*
G01X1125518Y747319D02*
X1108541Y752732D01*
G01D02*
X1095580Y748592D01*
G01X1108541Y753940D02*
X1095026Y749623D01*
G01X1125518Y747319D02*
X1108541Y752732D01*
G01X1126082Y748347D02*
X1108541Y753940D01*
G01X1190517Y207889D02*
X1146763Y236850D01*
G01X1190517Y207889D02*
X1146763Y236850D01*
G01X1160432Y212062D02*
X1151042Y218274D01*
G01X1325766Y146234D02*
X1159900Y211035D01*
G01X1326108Y147336D02*
X1160432Y212062D01*
G01D02*
X1151042Y218274D01*
G01X1326108Y147336D02*
X1160432Y212062D01*
G01X1325766Y146234D02*
X1159900Y211035D01*
G01X1140677Y209685D02*
X1139205Y210431D01*
G01X1144602Y207697D02*
X1143130Y208442D01*
G01X1285476Y136337D02*
X1147055Y206454D01*
G01X1146534Y205428D02*
X1146535D01*
G01X1284708Y135436D02*
X1146534Y205428D01*
G01X1140677Y209685D02*
X1139205Y210431D01*
G01X1144602Y207697D02*
X1143130Y208442D01*
G01X1146534Y205428D02*
X1146535D01*
G01X1285476Y136337D02*
X1147055Y206454D01*
G01X1284708Y135436D02*
X1146534Y205428D01*
G01X1285476Y136337D02*
X1147055Y206454D01*
G01X1174789Y263571D02*
X1210576Y239886D01*
G01X1175425Y264532D02*
X1211124Y240903D01*
G01X1175425Y264532D02*
X1211124Y240903D01*
G01X1174789Y263571D02*
X1210576Y239886D01*
G01X1143748Y270195D02*
X1199915Y233019D01*
G01X1143748Y270195D02*
X1199915Y233019D01*
G01X1141466Y256128D02*
X1139994Y256873D01*
G01X1337800Y156679D02*
X1143848Y254921D01*
G01X1141466Y256128D02*
X1139994Y256873D01*
G01X1337800Y156679D02*
X1143848Y254921D01*
G01X1140935Y240708D02*
X1139559Y241619D01*
G01X1144537Y238324D02*
X1143161Y239234D01*
G01X1140935Y240708D02*
X1139559Y241619D01*
G01X1144537Y238324D02*
X1143161Y239234D01*
G01X1145212Y222131D02*
X1143836Y223041D01*
G01X1148815Y219747D02*
X1147439Y220657D01*
G01X1145212Y222131D02*
X1143836Y223041D01*
G01X1148815Y219747D02*
X1147439Y220657D01*
G01X1183197Y301363D02*
X1184817Y301048D01*
G01X1178957Y302187D02*
X1180576Y301872D01*
G01X1183197Y301363D02*
X1184817Y301048D01*
G01X1178957Y302187D02*
X1180576Y301872D01*
G01X1148284Y282496D02*
X1175425Y264532D01*
G01X1144682Y284880D02*
X1146058Y283969D01*
G01X1141080Y287264D02*
X1142456Y286354D01*
G01X1148284Y282496D02*
X1175425Y264532D01*
G01X1144682Y284880D02*
X1146058Y283969D01*
G01X1141080Y287264D02*
X1142456Y286354D01*
G01X1140145Y272579D02*
X1141521Y271669D01*
G01X1136543Y274964D02*
X1137919Y274053D01*
G01X1140145Y272579D02*
X1141521Y271669D01*
G01X1136543Y274964D02*
X1137919Y274053D01*
G01X1183957Y317183D02*
X1185577Y316868D01*
G01X1179717Y318007D02*
X1181336Y317693D01*
G01X1183957Y317183D02*
X1185577Y316868D01*
G01X1179717Y318007D02*
X1181336Y317693D01*
G01X1167161Y346233D02*
X1201746Y338619D01*
G01X1162864Y347179D02*
X1164475Y346824D01*
G01X1167161Y346233D02*
X1201746Y338619D01*
G01X1162864Y347179D02*
X1164475Y346824D01*
G01X1170101Y352003D02*
X1200425Y345319D01*
G01X1165804Y352950D02*
X1167416Y352595D01*
G01X1170101Y352003D02*
X1200425Y345319D01*
G01X1165804Y352950D02*
X1167416Y352595D01*
G01X1170225Y359222D02*
X1231464Y345741D01*
G01X1170225Y359222D02*
X1231464Y345741D01*
G01X1165928Y360168D02*
X1167539Y359813D01*
G01X1165928Y360168D02*
X1167539Y359813D01*
G01X1167290Y366596D02*
X1165678Y366950D01*
G01X1236694Y351372D02*
X1169976Y366007D01*
G01X1167290Y366596D02*
X1165678Y366950D01*
G01X1236694Y351372D02*
X1169976Y366007D01*
G01X1196737Y620852D02*
X1174115Y653757D01*
G01X1196737Y620852D02*
X1174115Y653757D01*
G01X1164898Y667164D02*
X1144567Y696737D01*
G01X1167436Y663472D02*
X1166501Y664832D01*
G01X1169974Y659781D02*
X1169039Y661140D01*
G01X1172512Y656089D02*
X1171577Y657449D01*
G01X1164898Y667164D02*
X1144567Y696737D01*
G01X1167436Y663472D02*
X1166501Y664832D01*
G01X1169974Y659781D02*
X1169039Y661140D01*
G01X1172512Y656089D02*
X1171577Y657449D01*
G01X1169812Y670165D02*
X1142659Y709623D01*
G01X1172352Y666474D02*
X1171416Y667834D01*
G01X1174891Y662784D02*
X1173956Y664143D01*
G01X1177431Y659093D02*
X1176495Y660452D01*
G01X1201311Y624392D02*
X1179035Y656762D01*
G01X1169812Y670165D02*
X1142659Y709623D01*
G01X1172352Y666474D02*
X1171416Y667834D01*
G01X1174891Y662784D02*
X1173956Y664143D01*
G01X1177431Y659093D02*
X1176495Y660452D01*
G01X1201311Y624392D02*
X1179035Y656762D01*
G01X1462072Y261374D02*
X1138851Y729396D01*
G01X1175907Y673715D02*
X1149655Y711728D01*
G01X1178452Y670029D02*
X1177515Y671387D01*
G01X1180998Y666343D02*
X1180061Y667700D01*
G01X1183544Y662656D02*
X1182606Y664014D01*
G01X1462072Y261374D02*
X1138851Y729396D01*
G01X1462072Y261374D02*
X1138851Y729396D01*
G01X1462072Y261374D02*
X1138851Y729396D01*
G01X1462072Y261374D02*
X1138851Y729396D01*
G01X1175907Y673715D02*
X1149655Y711728D01*
G01X1462072Y261374D02*
X1138851Y729396D01*
G01X1178452Y670029D02*
X1177515Y671387D01*
G01X1462072Y261374D02*
X1138851Y729396D01*
G01X1180998Y666343D02*
X1180061Y667700D01*
G01X1462072Y261374D02*
X1138851Y729396D01*
G01X1183544Y662656D02*
X1182606Y664014D01*
G01X1462072Y261374D02*
X1138851Y729396D01*
G01X1462072Y261374D02*
X1138851Y729396D01*
G01X1462072Y261374D02*
X1138851Y729396D01*
G01X1462072Y261374D02*
X1138851Y729396D01*
G01X1462072Y261374D02*
X1138851Y729396D01*
G01X1462072Y261374D02*
X1138851Y729396D01*
G01X1462072Y261374D02*
X1138851Y729396D01*
G01X1460253Y276692D02*
X1148567Y729623D01*
G01X1180415Y681314D02*
X1155328Y717768D01*
G01X1182909Y677689D02*
X1181974Y679048D01*
G01X1185403Y674064D02*
X1184468Y675423D01*
G01X1460253Y276692D02*
X1148567Y729623D01*
G01X1460253Y276692D02*
X1148567Y729623D01*
G01X1460253Y276692D02*
X1148567Y729623D01*
G01X1180415Y681314D02*
X1155328Y717768D01*
G01X1460253Y276692D02*
X1148567Y729623D01*
G01X1182909Y677689D02*
X1181974Y679048D01*
G01X1460253Y276692D02*
X1148567Y729623D01*
G01X1185403Y674064D02*
X1184468Y675423D01*
G01X1460253Y276692D02*
X1148567Y729623D01*
G01X1460253Y276692D02*
X1148567Y729623D01*
G01X1460253Y276692D02*
X1148567Y729623D01*
G01X1460253Y276692D02*
X1148567Y729623D01*
G01X1460253Y276692D02*
X1148567Y729623D01*
G01X1460253Y276692D02*
X1148567Y729623D01*
G01X1460253Y276692D02*
X1148567Y729623D01*
G01X1460253Y276692D02*
X1148567Y729623D01*
G01X1460253Y276692D02*
X1148567Y729623D01*
G01X1138024Y706254D02*
X1137089Y707614D01*
G01X1140516Y702629D02*
X1139582Y703988D01*
G01X1143009Y699003D02*
X1142074Y700362D01*
G01X1138024Y706254D02*
X1137089Y707614D01*
G01X1140516Y702629D02*
X1139582Y703988D01*
G01X1143009Y699003D02*
X1142074Y700362D01*
G01X1138606Y715513D02*
X1137671Y716873D01*
G01X1141100Y711889D02*
X1140165Y713248D01*
G01X1138606Y715513D02*
X1137671Y716873D01*
G01X1141100Y711889D02*
X1140165Y713248D01*
G01X1140591Y724852D02*
X1137994Y728613D01*
G01X1143092Y721231D02*
X1142154Y722589D01*
G01X1145592Y717611D02*
X1144654Y718969D01*
G01X1148092Y713990D02*
X1147155Y715348D01*
G01X1140591Y724852D02*
X1137994Y728613D01*
G01X1143092Y721231D02*
X1142154Y722589D01*
G01X1145592Y717611D02*
X1144654Y718969D01*
G01X1148092Y713990D02*
X1147155Y715348D01*
G01X1148644Y727481D02*
X1147709Y728840D01*
G01X1151184Y723790D02*
X1150249Y725149D01*
G01X1153724Y720099D02*
X1152788Y721459D01*
G01X1148644Y727481D02*
X1147709Y728840D01*
G01X1151184Y723790D02*
X1150249Y725149D01*
G01X1153724Y720099D02*
X1152788Y721459D01*
G01X1341203Y147738D02*
X1189984Y206862D01*
G01X1341545Y148840D02*
X1190517Y207889D01*
G01X1341545Y148840D02*
X1190517Y207889D01*
G01X1341203Y147738D02*
X1189984Y206862D01*
G01X1210576Y239886D02*
X1355683Y177923D01*
G01X1211124Y240903D02*
X1356223Y178943D01*
G01X1211124Y240903D02*
X1356223Y178943D01*
G01X1210576Y239886D02*
X1355683Y177923D01*
G01X1199367Y232002D02*
X1377548Y155915D01*
G01X1199915Y233019D02*
X1378086Y156936D01*
G01X1199915Y233019D02*
X1378086Y156936D01*
G01X1199367Y232002D02*
X1377548Y155915D01*
G01X1188198Y316359D02*
X1235520Y307160D01*
G01X1188198Y316359D02*
X1235520Y307160D01*
G01X1187438Y300538D02*
X1246469Y289064D01*
G01X1187438Y300538D02*
X1246469Y289064D01*
G01X1201746Y338619D02*
X1406805Y207979D01*
G01X1202193Y339699D02*
X1407423Y208950D01*
G01X1201746Y338619D02*
X1406805Y207979D01*
G01X1201746Y338619D02*
X1406805Y207979D01*
G01X1202193Y339699D02*
X1407423Y208950D01*
G01X1200872Y346399D02*
X1460734Y180849D01*
G01X1200425Y345319D02*
X1459902Y180015D01*
G01X1200872Y346399D02*
X1460734Y180849D01*
G01X1200425Y345319D02*
X1459902Y180015D01*
G01X1200872Y346399D02*
X1460734Y180849D01*
G01X1231936Y346815D02*
X1467653Y181463D01*
G01X1231464Y345741D02*
X1466806Y180652D01*
G01X1231464Y345741D02*
X1466806Y180652D01*
G01X1231936Y346815D02*
X1467653Y181463D01*
G01X1226898Y576980D02*
X1203280Y611334D01*
G01X1229391Y573354D02*
X1228456Y574713D01*
G01X1453009Y248089D02*
X1230949Y571088D01*
G01X1226898Y576980D02*
X1203280Y611334D01*
G01X1229391Y573354D02*
X1228456Y574713D01*
G01X1453009Y248089D02*
X1230949Y571088D01*
G01X1232082Y579675D02*
X1207858Y614877D01*
G01X1232082Y579675D02*
X1207858Y614877D01*
G01X1238455Y583142D02*
X1214493Y617840D01*
G01X1238455Y583142D02*
X1214493Y617840D01*
G01X1199229Y617226D02*
X1198295Y618586D01*
G01X1201722Y613601D02*
X1200787Y614960D01*
G01X1199229Y617226D02*
X1198295Y618586D01*
G01X1201722Y613601D02*
X1200787Y614960D01*
G01X1203805Y620767D02*
X1202870Y622126D01*
G01X1206299Y617142D02*
X1205364Y618502D01*
G01X1203805Y620767D02*
X1202870Y622126D01*
G01X1206299Y617142D02*
X1205364Y618502D01*
G01X1207930Y627344D02*
X1185152Y660328D01*
G01X1210430Y623723D02*
X1209493Y625081D01*
G01X1212931Y620103D02*
X1211993Y621461D01*
G01X1207930Y627344D02*
X1185152Y660328D01*
G01X1210430Y623723D02*
X1209493Y625081D01*
G01X1212931Y620103D02*
X1211993Y621461D01*
G01X1424323Y326875D02*
X1186962Y671799D01*
G01X1424323Y326875D02*
X1186962Y671799D01*
G01X1235086Y306072D02*
X1401465Y200102D01*
G01X1235520Y307160D02*
X1402289Y200941D01*
G01X1235520Y307160D02*
X1402289Y200941D01*
G01X1235086Y306072D02*
X1401465Y200102D01*
G01X1246035Y287976D02*
X1372213Y207589D01*
G01X1246469Y289064D02*
X1373046Y208422D01*
G01X1246469Y289064D02*
X1373046Y208422D01*
G01X1246035Y287976D02*
X1372213Y207589D01*
G01X1237166Y352446D02*
X1470691Y188631D01*
G01X1353269Y269596D02*
X1236694Y351372D01*
G01X1353269Y269596D02*
X1236694Y351372D01*
G01X1237166Y352446D02*
X1470691Y188631D01*
G01X1237166Y352446D02*
X1470691Y188631D01*
G01X1458269Y250981D02*
X1236135Y573785D01*
G01X1458269Y250981D02*
X1236135Y573785D01*
G01X1461059Y260815D02*
X1242518Y577259D01*
G01X1461059Y260815D02*
X1242518Y577259D01*
G01X1234576Y576051D02*
X1233641Y577410D01*
G01X1234576Y576051D02*
X1233641Y577410D01*
G01X1240956Y579521D02*
X1240018Y580879D01*
G01X1240956Y579521D02*
X1240018Y580879D01*
G01X1308628Y104461D02*
X1285476Y136337D01*
G01X1307896Y103511D02*
X1284708Y135436D01*
G01X1350913Y88052D02*
X1308628Y104461D01*
G01X1392982Y70492D02*
X1307896Y103511D01*
G01X1392982Y70492D02*
X1307896Y103511D01*
G01D02*
X1284708Y135436D01*
G01X1308628Y104461D02*
X1285476Y136337D01*
G01X1392982Y70492D02*
X1307896Y103511D01*
G01X1350913Y88052D02*
X1308628Y104461D01*
G01X1386146Y132167D02*
X1325766Y146234D01*
G01X1386624Y133237D02*
X1326108Y147336D01*
G01X1386624Y133237D02*
X1326108Y147336D01*
G01X1386146Y132167D02*
X1325766Y146234D01*
G01X1393198Y71642D02*
X1350913Y88053D01*
G01X1393198Y71642D02*
X1350913Y88053D01*
G01X1355683Y177923D02*
X1422181Y135380D01*
G01X1355683Y177923D02*
X1422181Y135380D01*
G01X1377548Y155915D02*
X1420428Y128589D01*
G01X1378086Y156936D02*
X1378166Y156886D01*
G01X1377548Y155915D02*
X1420428Y128589D01*
G01X1378086Y156936D02*
X1378166Y156886D01*
G01X1377548Y155915D02*
X1420428Y128589D01*
G01X1386175Y144227D02*
X1337404Y155590D01*
G01X1386628Y145303D02*
X1337800Y156679D01*
G01X1386628Y145303D02*
X1337800Y156679D01*
G01X1386175Y144227D02*
X1337404Y155590D01*
G01X1388663Y136682D02*
X1341203Y147738D01*
G01X1389117Y137758D02*
X1341545Y148840D01*
G01X1389117Y137758D02*
X1341545Y148840D01*
G01X1388663Y136682D02*
X1341203Y147738D01*
G01X1373046Y208422D02*
X1387964Y185009D01*
G01X1372213Y207589D02*
X1379664Y195894D01*
G01X1373046Y208422D02*
X1387964Y185009D01*
G01X1373046Y208422D02*
X1387964Y185009D01*
G01X1372213Y207589D02*
X1379664Y195894D01*
G01X1356223Y178943D02*
X1423046Y136193D01*
G01X1356223Y178943D02*
X1423046Y136193D01*
G01X1469844Y187820D02*
X1353269Y269595D01*
G01X1469844Y187820D02*
X1353269Y269595D01*
G01X1424370Y70489D02*
X1426013D01*
G01X1424370Y71639D02*
X1426014D01*
G01X1423203Y70971D02*
G03X1424370Y70489I1166J1168D01*
G01X1424017Y71785D02*
G03X1424370Y71639I353J354D01*
G01X1422939Y71236D02*
X1423203Y70971D01*
G01X1423753Y72049D02*
X1424017Y71785D01*
G01X1422457Y72402D02*
G03X1422939Y71236I1650J-1D01*
G01X1423607Y72402D02*
G03X1423753Y72049I500J0D01*
G01X1422457Y124939D02*
Y72402D01*
G01X1423607Y125238D02*
Y72402D01*
G01X1424370Y71639D02*
X1426014D01*
G01X1424370Y70489D02*
X1426013D01*
G01X1424017Y71785D02*
G03X1424370Y71639I353J354D01*
G01X1423203Y70971D02*
G03X1424370Y70489I1166J1168D01*
G01X1423753Y72049D02*
X1424017Y71785D01*
G01X1422939Y71236D02*
X1423203Y70971D01*
G01X1423607Y72402D02*
G03X1423753Y72049I500J0D01*
G01X1422457Y72402D02*
G03X1422939Y71236I1650J-1D01*
G01X1423607Y125238D02*
Y72402D01*
G01X1422457Y124939D02*
Y72402D01*
G01X1415370Y76339D02*
Y121705D01*
G01X1416520Y76339D02*
Y122004D01*
G01X1415852Y75173D02*
G02X1415370Y76339I1168J1165D01*
G01X1416666Y75986D02*
G02X1416520Y76339I354J353D01*
G01X1416116Y74908D02*
X1415852Y75173D01*
G01X1416930Y75722D02*
X1416666Y75986D01*
G01X1417283Y74426D02*
G02X1416116Y74908I-1J1650D01*
G01X1417283Y75576D02*
G02X1416930Y75722I0J500D01*
G01X1418926Y74426D02*
X1417283D01*
G01X1418927Y75576D02*
X1417283D01*
G01X1416520Y76339D02*
Y122004D01*
G01X1415370Y76339D02*
Y121705D01*
G01X1416666Y75986D02*
G02X1416520Y76339I354J353D01*
G01X1415852Y75173D02*
G02X1415370Y76339I1168J1165D01*
G01X1416930Y75722D02*
X1416666Y75986D01*
G01X1416116Y74908D02*
X1415852Y75173D01*
G01X1417283Y75576D02*
G02X1416930Y75722I0J500D01*
G01X1417283Y74426D02*
G02X1416116Y74908I-1J1650D01*
G01X1418927Y75576D02*
X1417283D01*
G01X1418926Y74426D02*
X1417283D01*
G01X1408284Y72402D02*
Y122980D01*
G01X1409434Y72402D02*
Y123279D01*
G01X1408766Y71236D02*
G02X1408284Y72402I1168J1165D01*
G01X1409580Y72049D02*
G02X1409434Y72402I354J353D01*
G01X1409030Y70971D02*
X1408766Y71236D01*
G01X1409844Y71785D02*
X1409580Y72049D01*
G01X1410197Y70489D02*
G02X1409030Y70971I-1J1650D01*
G01X1410197Y71639D02*
G02X1409844Y71785I0J500D01*
G01X1411840Y70489D02*
X1410197D01*
G01X1411841Y71639D02*
X1410197D01*
G01X1409434Y72402D02*
Y123279D01*
G01X1408284Y72402D02*
Y122980D01*
G01X1409580Y72049D02*
G02X1409434Y72402I354J353D01*
G01X1408766Y71236D02*
G02X1408284Y72402I1168J1165D01*
G01X1409844Y71785D02*
X1409580Y72049D01*
G01X1409030Y70971D02*
X1408766Y71236D01*
G01X1410197Y71639D02*
G02X1409844Y71785I0J500D01*
G01X1410197Y70489D02*
G02X1409030Y70971I-1J1650D01*
G01X1411841Y71639D02*
X1410197D01*
G01X1411840Y70489D02*
X1410197D01*
G01X1401197Y76339D02*
Y120977D01*
G01X1402347Y76339D02*
Y121276D01*
G01X1403110Y74426D02*
G02X1401197Y76339I0J1913D01*
G01X1403110Y75576D02*
G02X1402347Y76339I0J763D01*
G01X1404753Y74426D02*
X1403110D01*
G01X1404754Y75576D02*
X1403110D01*
G01X1402347Y76339D02*
Y121276D01*
G01X1401197Y76339D02*
Y120977D01*
G01X1403110Y75576D02*
G02X1402347Y76339I0J763D01*
G01X1403110Y74426D02*
G02X1401197Y76339I0J1913D01*
G01X1404754Y75576D02*
X1403110D01*
G01X1404753Y74426D02*
X1403110D01*
G01X1397495Y71642D02*
X1393198D01*
G01X1397503Y70492D02*
X1392982D01*
G01X1397503D02*
X1392982D01*
G01X1397495Y71642D02*
X1393198D01*
G01X1401465Y200102D02*
X1443717Y136370D01*
G01X1401465Y200102D02*
X1443717Y136370D01*
G01X1412614Y166311D02*
X1436630Y123128D01*
G01X1413491Y167101D02*
X1437780Y123427D01*
G01X1413491Y167101D02*
X1437780Y123427D01*
G01X1412614Y166311D02*
X1436630Y123128D01*
G01X1422181Y135380D02*
X1429543Y122147D01*
G01X1423046Y136193D02*
X1430693Y122446D01*
G01X1423046Y136193D02*
X1430693Y122446D01*
G01X1422181Y135380D02*
X1429543Y122147D01*
G01X1420428Y128589D02*
X1422457Y124939D01*
G01X1421292Y129403D02*
X1423607Y125238D01*
G01X1378166Y156885D02*
X1421292Y129403D01*
G01D02*
X1423607Y125238D01*
G01X1420428Y128589D02*
X1422457Y124939D01*
G01X1378166Y156885D02*
X1421292Y129403D01*
G01X1411998Y127772D02*
X1386175Y144227D01*
G01X1386793Y145198D02*
X1386628Y145303D01*
G01X1412862Y128586D02*
X1386793Y145197D01*
G01X1415370Y121705D02*
X1411998Y127772D01*
G01X1416520Y122004D02*
X1412862Y128586D01*
G01X1386793Y145198D02*
X1386628Y145303D01*
G01X1411998Y127772D02*
X1386175Y144227D01*
G01X1412862Y128586D02*
X1386793Y145197D01*
G01X1411998Y127772D02*
X1386175Y144227D01*
G01X1416520Y122004D02*
X1412862Y128586D01*
G01X1415370Y121705D02*
X1411998Y127772D01*
G01X1407249Y124839D02*
X1388663Y136681D01*
G01X1398574Y131731D02*
X1389116Y137757D01*
G01X1408113Y125653D02*
X1398574Y131731D01*
G01X1408284Y122980D02*
X1407249Y124839D01*
G01X1409434Y123279D02*
X1408113Y125653D01*
G01X1398574Y131731D02*
X1389116Y137757D01*
G01X1407249Y124839D02*
X1388663Y136681D01*
G01X1408113Y125653D02*
X1398574Y131731D01*
G01X1407249Y124839D02*
X1388663Y136681D01*
G01X1409434Y123279D02*
X1408113Y125653D01*
G01X1408284Y122980D02*
X1407249Y124839D01*
G01X1400620Y122014D02*
X1386146Y132167D01*
G01X1401497Y122804D02*
X1386624Y133237D01*
G01X1401197Y120977D02*
X1400620Y122014D01*
G01X1402347Y121276D02*
X1401497Y122804D01*
G01D02*
X1386624Y133237D01*
G01X1400620Y122014D02*
X1386146Y132167D01*
G01X1402347Y121276D02*
X1401497Y122804D01*
G01X1401197Y120977D02*
X1400620Y122014D01*
G01X1402289Y200941D02*
X1444867Y136717D01*
G01X1402289Y200941D02*
X1444867Y136717D01*
G01X1387116Y184198D02*
X1412614Y166311D01*
G01X1387964Y185009D02*
X1413491Y167101D01*
G01X1379664Y195895D02*
X1387116Y184198D01*
G01X1387964Y185009D02*
X1413491Y167101D01*
G01X1387116Y184198D02*
X1412614Y166311D01*
G01X1379664Y195895D02*
X1387116Y184198D01*
G01X1407629Y208818D02*
X1431065Y173409D01*
G01X1406805Y207979D02*
X1430231Y172585D01*
G01X1407423Y208950D02*
X1407629Y208818D01*
G01X1406805Y207979D02*
X1430231Y172585D01*
G01X1407629Y208818D02*
X1431065Y173409D01*
G01X1407423Y208950D02*
X1407629Y208818D01*
G01X1426817Y323250D02*
X1425882Y324609D01*
G01X1426817Y323250D02*
X1425882Y324609D01*
G01X1445630Y74426D02*
X1447273D01*
G01X1445630Y75576D02*
X1447274D01*
G01X1444463Y74908D02*
G03X1445630Y74426I1166J1168D01*
G01X1445277Y75722D02*
G03X1445630Y75576I353J354D01*
G01X1444199Y75173D02*
X1444463Y74908D01*
G01X1445013Y75986D02*
X1445277Y75722D01*
G01X1443717Y76339D02*
G03X1444199Y75173I1650J-1D01*
G01X1444867Y76339D02*
G03X1445013Y75986I500J0D01*
G01X1443717Y136370D02*
Y76339D01*
G01X1444867Y136717D02*
Y76339D01*
G01X1445630Y75576D02*
X1447274D01*
G01X1445630Y74426D02*
X1447273D01*
G01X1445277Y75722D02*
G03X1445630Y75576I353J354D01*
G01X1444463Y74908D02*
G03X1445630Y74426I1166J1168D01*
G01X1445013Y75986D02*
X1445277Y75722D01*
G01X1444199Y75173D02*
X1444463Y74908D01*
G01X1444867Y76339D02*
G03X1445013Y75986I500J0D01*
G01X1443717Y76339D02*
G03X1444199Y75173I1650J-1D01*
G01X1444867Y136717D02*
Y76339D01*
G01X1443717Y136370D02*
Y76339D01*
G01X1438543Y70489D02*
X1440186D01*
G01X1438543Y71639D02*
X1440187D01*
G01X1437376Y70971D02*
G03X1438543Y70489I1166J1168D01*
G01X1438190Y71785D02*
G03X1438543Y71639I353J354D01*
G01X1437112Y71236D02*
X1437376Y70971D01*
G01X1437926Y72049D02*
X1438190Y71785D01*
G01X1436630Y72402D02*
G03X1437112Y71236I1650J-1D01*
G01X1437780Y72402D02*
G03X1437926Y72049I500J0D01*
G01X1436630Y123128D02*
Y72402D01*
G01X1437780Y123427D02*
Y72402D01*
G01X1438543Y71639D02*
X1440187D01*
G01X1438543Y70489D02*
X1440186D01*
G01X1438190Y71785D02*
G03X1438543Y71639I353J354D01*
G01X1437376Y70971D02*
G03X1438543Y70489I1166J1168D01*
G01X1437926Y72049D02*
X1438190Y71785D01*
G01X1437112Y71236D02*
X1437376Y70971D01*
G01X1437780Y72402D02*
G03X1437926Y72049I500J0D01*
G01X1436630Y72402D02*
G03X1437112Y71236I1650J-1D01*
G01X1437780Y123427D02*
Y72402D01*
G01X1436630Y123128D02*
Y72402D01*
G01X1431456Y74426D02*
X1433099D01*
G01X1431456Y75576D02*
X1433100D01*
G01X1430289Y74908D02*
G03X1431456Y74426I1166J1168D01*
G01X1431103Y75722D02*
G03X1431456Y75576I353J354D01*
G01X1430025Y75173D02*
X1430289Y74908D01*
G01X1430839Y75986D02*
X1431103Y75722D01*
G01X1429543Y76339D02*
G03X1430025Y75173I1650J-1D01*
G01X1430693Y76339D02*
G03X1430839Y75986I500J0D01*
G01X1429543Y122147D02*
Y76339D01*
G01X1430693Y122446D02*
Y76339D01*
G01X1431456Y75576D02*
X1433100D01*
G01X1431456Y74426D02*
X1433099D01*
G01X1431103Y75722D02*
G03X1431456Y75576I353J354D01*
G01X1430289Y74908D02*
G03X1431456Y74426I1166J1168D01*
G01X1430839Y75986D02*
X1431103Y75722D01*
G01X1430025Y75173D02*
X1430289Y74908D01*
G01X1430693Y76339D02*
G03X1430839Y75986I500J0D01*
G01X1429543Y76339D02*
G03X1430025Y75173I1650J-1D01*
G01X1430693Y122446D02*
Y76339D01*
G01X1429543Y122147D02*
Y76339D01*
G01X1472835Y145062D02*
X1487386Y122239D01*
G01X1471993Y144240D02*
X1486236Y121903D01*
G01X1431065Y173409D02*
X1472835Y145062D01*
G01X1430231Y172585D02*
X1471995Y144241D01*
G01X1471993Y144240D02*
X1486236Y121903D01*
G01X1472835Y145062D02*
X1487386Y122239D01*
G01X1430231Y172585D02*
X1471995Y144241D01*
G01X1431065Y173409D02*
X1472835Y145062D01*
G01X1460734Y180849D02*
X1494472Y127939D01*
G01X1459901Y180015D02*
X1476611Y153809D01*
G01X1460734Y180849D02*
X1494472Y127939D01*
G01X1459901Y180015D02*
X1476611Y153809D01*
G01X1460734Y180849D02*
X1494472Y127939D01*
G01X1485403Y175251D02*
X1454022Y248647D01*
G01X1484391Y174692D02*
X1453009Y248089D01*
G01X1484391Y174692D02*
X1453009Y248089D01*
G01X1485403Y175251D02*
X1454022Y248647D01*
G01X1459902Y180015D02*
X1459901D01*
G01X1459902D02*
X1459901D01*
G01X1467653Y181463D02*
X1501559Y128281D01*
G01X1466806Y180652D02*
X1500409Y127945D01*
G01X1466806Y180652D02*
X1500409Y127945D01*
G01X1467653Y181463D02*
X1501559Y128281D01*
G01X1470691Y188631D02*
X1508646Y129108D01*
G01X1507496Y128772D02*
X1469844Y187820D01*
G01X1507496Y128772D02*
X1469844Y187820D01*
G01X1470691Y188631D02*
X1508646Y129108D01*
G01X1491049Y177233D02*
X1459282Y251539D01*
G01X1490037Y176674D02*
X1458269Y250981D01*
G01X1490037Y176674D02*
X1458269Y250981D01*
G01X1491049Y177233D02*
X1459282Y251539D01*
G01X1498370Y176494D02*
X1462072Y261374D01*
G01X1497358Y175935D02*
X1461059Y260815D01*
G01X1497358Y175935D02*
X1461059Y260815D01*
G01X1498370Y176494D02*
X1462072Y261374D01*
G01X1501390Y180449D02*
X1460253Y276692D01*
G01X1500400Y179839D02*
X1459240Y276134D01*
G01X1500400Y179839D02*
X1459240Y276134D01*
G01X1501390Y180449D02*
X1460253Y276692D01*
G01X1451757Y287008D02*
X1433364Y313735D01*
G01X1454251Y283383D02*
X1453316Y284743D01*
G01X1456746Y279759D02*
X1455810Y281118D01*
G01X1459240Y276134D02*
X1458305Y277493D01*
G01X1451757Y287008D02*
X1433364Y313735D01*
G01X1454251Y283383D02*
X1453316Y284743D01*
G01X1456746Y279759D02*
X1455810Y281118D01*
G01X1459240Y276134D02*
X1458305Y277493D01*
G01X1429311Y319626D02*
X1428376Y320985D01*
G01X1431805Y316001D02*
X1430870Y317360D01*
G01X1429311Y319626D02*
X1428376Y320985D01*
G01X1431805Y316001D02*
X1430870Y317360D01*
G01X1515732Y72402D02*
Y131444D01*
G01X1514582Y72402D02*
Y131084D01*
G01X1515250Y71236D02*
G03X1515732Y72402I-1168J1165D01*
G01X1514436Y72049D02*
G03X1514582Y72402I-354J353D01*
G01X1514986Y70971D02*
X1515250Y71236D01*
G01X1514172Y71785D02*
X1514436Y72049D01*
G01X1513819Y70489D02*
G03X1514986Y70971I1J1650D01*
G01X1513819Y71639D02*
G03X1514172Y71785I0J500D01*
G01X1512176Y70489D02*
X1513819D01*
G01X1512175Y71639D02*
X1513819D01*
G01X1514582Y72402D02*
Y131084D01*
G01X1515732Y72402D02*
Y131444D01*
G01X1514436Y72049D02*
G03X1514582Y72402I-354J353D01*
G01X1515250Y71236D02*
G03X1515732Y72402I-1168J1165D01*
G01X1514172Y71785D02*
X1514436Y72049D01*
G01X1514986Y70971D02*
X1515250Y71236D01*
G01X1513819Y71639D02*
G03X1514172Y71785I0J500D01*
G01X1513819Y70489D02*
G03X1514986Y70971I1J1650D01*
G01X1512175Y71639D02*
X1513819D01*
G01X1512176Y70489D02*
X1513819D01*
G01X1522819Y76339D02*
Y131327D01*
G01X1521669Y76339D02*
Y130967D01*
G01X1522337Y75173D02*
G03X1522819Y76339I-1168J1165D01*
G01X1521523Y75986D02*
G03X1521669Y76339I-354J353D01*
G01X1522073Y74908D02*
X1522337Y75173D01*
G01X1521259Y75722D02*
X1521523Y75986D01*
G01X1520906Y74426D02*
G03X1522073Y74908I1J1650D01*
G01X1520906Y75576D02*
G03X1521259Y75722I0J500D01*
G01X1519263Y74426D02*
X1520906D01*
G01X1519262Y75576D02*
X1520906D01*
G01X1521669Y76339D02*
Y130967D01*
G01X1522819Y76339D02*
Y131327D01*
G01X1521523Y75986D02*
G03X1521669Y76339I-354J353D01*
G01X1522337Y75173D02*
G03X1522819Y76339I-1168J1165D01*
G01X1521259Y75722D02*
X1521523Y75986D01*
G01X1522073Y74908D02*
X1522337Y75173D01*
G01X1520906Y75576D02*
G03X1521259Y75722I0J500D01*
G01X1520906Y74426D02*
G03X1522073Y74908I1J1650D01*
G01X1519262Y75576D02*
X1520906D01*
G01X1519263Y74426D02*
X1520906D01*
G01X1485473Y70489D02*
X1483830D01*
G01X1485473Y71639D02*
X1483829D01*
G01X1486640Y70971D02*
G02X1485473Y70489I-1166J1168D01*
G01X1485826Y71785D02*
G02X1485473Y71639I-353J354D01*
G01X1486904Y71236D02*
X1486640Y70971D01*
G01X1486090Y72049D02*
X1485826Y71785D01*
G01X1487386Y72402D02*
G02X1486904Y71236I-1650J-1D01*
G01X1486236Y72402D02*
G02X1486090Y72049I-500J0D01*
G01X1487386Y122239D02*
Y72402D01*
G01X1486236Y121903D02*
Y72402D01*
G01X1485473Y71639D02*
X1483829D01*
G01X1485473Y70489D02*
X1483830D01*
G01X1485826Y71785D02*
G02X1485473Y71639I-353J354D01*
G01X1486640Y70971D02*
G02X1485473Y70489I-1166J1168D01*
G01X1486090Y72049D02*
X1485826Y71785D01*
G01X1486904Y71236D02*
X1486640Y70971D01*
G01X1486236Y72402D02*
G02X1486090Y72049I-500J0D01*
G01X1487386Y72402D02*
G02X1486904Y71236I-1650J-1D01*
G01X1486236Y121903D02*
Y72402D01*
G01X1487386Y122239D02*
Y72402D01*
G01X1492559Y74426D02*
X1490916D01*
G01X1492559Y75576D02*
X1490915D01*
G01X1493726Y74908D02*
G02X1492559Y74426I-1166J1168D01*
G01X1492912Y75722D02*
G02X1492559Y75576I-353J354D01*
G01X1493990Y75173D02*
X1493726Y74908D01*
G01X1493176Y75986D02*
X1492912Y75722D01*
G01X1494472Y76339D02*
G02X1493990Y75173I-1650J-1D01*
G01X1493322Y76339D02*
G02X1493176Y75986I-500J0D01*
G01X1494472Y127939D02*
Y76339D01*
G01X1493322Y127603D02*
Y76339D01*
G01X1492559Y75576D02*
X1490915D01*
G01X1492559Y74426D02*
X1490916D01*
G01X1492912Y75722D02*
G02X1492559Y75576I-353J354D01*
G01X1493726Y74908D02*
G02X1492559Y74426I-1166J1168D01*
G01X1493176Y75986D02*
X1492912Y75722D01*
G01X1493990Y75173D02*
X1493726Y74908D01*
G01X1493322Y76339D02*
G02X1493176Y75986I-500J0D01*
G01X1494472Y76339D02*
G02X1493990Y75173I-1650J-1D01*
G01X1493322Y127603D02*
Y76339D01*
G01X1494472Y127939D02*
Y76339D01*
G01X1499646Y70489D02*
X1498003D01*
G01X1499646Y71639D02*
X1498002D01*
G01X1500813Y70971D02*
G02X1499646Y70489I-1166J1168D01*
G01X1499999Y71785D02*
G02X1499646Y71639I-353J354D01*
G01X1501077Y71236D02*
X1500813Y70971D01*
G01X1500263Y72049D02*
X1499999Y71785D01*
G01X1501559Y72402D02*
G02X1501077Y71236I-1650J-1D01*
G01X1500409Y72402D02*
G02X1500263Y72049I-500J0D01*
G01X1501559Y128281D02*
Y72402D01*
G01X1500409Y127945D02*
Y72402D01*
G01X1499646Y71639D02*
X1498002D01*
G01X1499646Y70489D02*
X1498003D01*
G01X1499999Y71785D02*
G02X1499646Y71639I-353J354D01*
G01X1500813Y70971D02*
G02X1499646Y70489I-1166J1168D01*
G01X1500263Y72049D02*
X1499999Y71785D01*
G01X1501077Y71236D02*
X1500813Y70971D01*
G01X1500409Y72402D02*
G02X1500263Y72049I-500J0D01*
G01X1501559Y72402D02*
G02X1501077Y71236I-1650J-1D01*
G01X1500409Y127945D02*
Y72402D01*
G01X1501559Y128281D02*
Y72402D01*
G01X1506733Y74426D02*
X1505090D01*
G01X1505089Y75576D02*
X1506733D01*
G01X1507900Y74908D02*
G02X1506733Y74426I-1166J1168D01*
G01Y75576D02*
G03X1507086Y75722I0J500D01*
G01X1508164Y75173D02*
X1507900Y74908D01*
G01X1507086Y75722D02*
X1507350Y75986D01*
G01X1508646Y76339D02*
G02X1508164Y75173I-1650J-1D01*
G01X1507350Y75986D02*
G03X1507496Y76339I-354J353D01*
G01X1508646Y129108D02*
Y76339D01*
G01X1507496D02*
Y128772D01*
G01Y76339D02*
Y128772D01*
G01X1508646Y129108D02*
Y76339D01*
G01X1507350Y75986D02*
G03X1507496Y76339I-354J353D01*
G01X1508646D02*
G02X1508164Y75173I-1650J-1D01*
G01X1507086Y75722D02*
X1507350Y75986D01*
G01X1508164Y75173D02*
X1507900Y74908D01*
G01X1506733Y75576D02*
G03X1507086Y75722I0J500D01*
G01X1507900Y74908D02*
G02X1506733Y74426I-1166J1168D01*
G01X1505089Y75576D02*
X1506733D01*
G01Y74426D02*
X1505090D01*
G01X1515732Y131444D02*
X1485403Y175251D01*
G01X1514582Y131084D02*
X1484391Y174692D01*
G01X1514582Y131084D02*
X1484391Y174692D01*
G01X1515732Y131444D02*
X1485403Y175251D01*
G01X1522819Y131327D02*
X1491049Y177233D01*
G01X1521669Y130967D02*
X1490037Y176674D01*
G01X1521669Y130967D02*
X1490037Y176674D01*
G01X1522819Y131327D02*
X1491049Y177233D01*
G01X1529905Y130976D02*
X1498370Y176494D01*
G01X1528755Y130616D02*
X1497358Y175935D01*
G01X1528755Y130616D02*
X1497358Y175935D01*
G01X1529905Y130976D02*
X1498370Y176494D01*
G01X1535842Y128618D02*
X1500400Y179839D01*
G01X1519116Y154812D02*
X1511788Y165403D01*
G01X1535842Y128618D02*
X1500400Y179839D01*
G01X1536894Y129119D02*
X1519116Y154812D01*
G01X1535842Y128618D02*
X1500400Y179839D01*
G01X1535842Y128618D02*
X1500400Y179839D01*
G01X1519116Y154812D02*
X1511788Y165403D01*
G01X1536894Y129119D02*
X1519116Y154812D01*
G01X1476611Y153810D02*
X1493322Y127603D01*
G01X1476611Y153810D02*
X1493322Y127603D01*
G01X1511788Y165403D02*
X1501444Y180352D01*
G01X1511788Y165403D02*
X1501444Y180352D01*
G01X1529905Y72402D02*
Y130976D01*
G01X1528755Y72402D02*
Y130616D01*
G01X1529423Y71236D02*
G03X1529905Y72402I-1168J1165D01*
G01X1528609Y72049D02*
G03X1528755Y72402I-354J353D01*
G01X1529159Y70971D02*
X1529423Y71236D01*
G01X1528345Y71785D02*
X1528609Y72049D01*
G01X1527992Y70489D02*
G03X1529159Y70971I1J1650D01*
G01X1527992Y71639D02*
G03X1528345Y71785I0J500D01*
G01X1526349Y70489D02*
X1527992D01*
G01X1526348Y71639D02*
X1527992D01*
G01X1528755Y72402D02*
Y130616D01*
G01X1529905Y72402D02*
Y130976D01*
G01X1528609Y72049D02*
G03X1528755Y72402I-354J353D01*
G01X1529423Y71236D02*
G03X1529905Y72402I-1168J1165D01*
G01X1528345Y71785D02*
X1528609Y72049D01*
G01X1529159Y70971D02*
X1529423Y71236D01*
G01X1527992Y71639D02*
G03X1528345Y71785I0J500D01*
G01X1527992Y70489D02*
G03X1529159Y70971I1J1650D01*
G01X1526348Y71639D02*
X1527992D01*
G01X1526349Y70489D02*
X1527992D01*
G01X1536992Y76339D02*
Y128806D01*
G01X1535842Y76339D02*
Y128618D01*
G01X1536510Y75173D02*
G03X1536992Y76339I-1168J1165D01*
G01X1535696Y75986D02*
G03X1535842Y76339I-354J353D01*
G01X1536246Y74908D02*
X1536510Y75173D01*
G01X1535432Y75722D02*
X1535696Y75986D01*
G01X1535079Y74426D02*
G03X1536246Y74908I1J1650D01*
G01X1535079Y75576D02*
G03X1535432Y75722I0J500D01*
G01X1533436Y74426D02*
X1535079D01*
G01X1533435Y75576D02*
X1535079D01*
G01X1535842Y76339D02*
Y128618D01*
G01X1536992Y76339D02*
Y128806D01*
G01X1535696Y75986D02*
G03X1535842Y76339I-354J353D01*
G01X1536510Y75173D02*
G03X1536992Y76339I-1168J1165D01*
G01X1535432Y75722D02*
X1535696Y75986D01*
G01X1536246Y74908D02*
X1536510Y75173D01*
G01X1535079Y75576D02*
G03X1535432Y75722I0J500D01*
G01X1535079Y74426D02*
G03X1536246Y74908I1J1650D01*
G01X1533435Y75576D02*
X1535079D01*
G01X1533436Y74426D02*
X1535079D01*
G54D13*
G01X1098826Y1176676D02*
Y1174970D01*
G01X1097526Y1176676D02*
Y1174970D01*
G01X1098972Y1177029D02*
G03X1098826Y1176676I354J-353D01*
G01X1098052Y1177948D02*
G03X1097526Y1176676I1275J-1272D01*
G01X1099473Y1177323D02*
G03X1099120Y1177177I0J-500D01*
G01X1099473Y1178623D02*
G03X1098201Y1178097I0J-1801D01*
G01X1133552Y1177323D02*
X1099473D01*
G01X1133648Y1178623D02*
X1099473D01*
G01X1140874Y1175700D02*
X1133552Y1177323D01*
G01X1136800Y1177935D02*
X1133740Y1178613D01*
G01X1097526Y1176676D02*
Y1174970D01*
G01X1098826Y1176676D02*
Y1174970D01*
G01X1098052Y1177948D02*
G03X1097526Y1176676I1275J-1272D01*
G01X1098972Y1177029D02*
G03X1098826Y1176676I354J-353D01*
G01X1099473Y1178623D02*
G03X1098201Y1178097I0J-1801D01*
G01X1099473Y1177323D02*
G03X1099120Y1177177I0J-500D01*
G01X1133648Y1178623D02*
X1099473D01*
G01X1133552Y1177323D02*
X1099473D01*
G01X1136800Y1177935D02*
X1133740Y1178613D01*
G01X1140874Y1175700D02*
X1133552Y1177323D01*
G01X1140874Y1175700D02*
X1133552Y1177323D01*
G01X1103527Y1198583D02*
X1137155D01*
G01X1103527Y1199883D02*
X1137298D01*
G01X1103174Y1198437D02*
G02X1103527Y1198583I353J-354D01*
G01X1102255Y1199357D02*
G02X1103527Y1199883I1272J-1275D01*
G01X1102909Y1198172D02*
X1103174Y1198437D01*
G01X1101989Y1199091D02*
X1102255Y1199357D01*
G01X1102763Y1197819D02*
G02X1102909Y1198172I500J0D01*
G01X1101463Y1197819D02*
G02X1101989Y1199091I1801J0D01*
G01X1102763Y1196213D02*
Y1197819D01*
G01X1101463Y1196213D02*
Y1197819D01*
G01X1103527Y1199883D02*
X1137298D01*
G01X1103527Y1198583D02*
X1137155D01*
G01X1102255Y1199357D02*
G02X1103527Y1199883I1272J-1275D01*
G01X1103174Y1198437D02*
G02X1103527Y1198583I353J-354D01*
G01X1101989Y1199091D02*
X1102255Y1199357D01*
G01X1102909Y1198172D02*
X1103174Y1198437D01*
G01X1101463Y1197819D02*
G02X1101989Y1199091I1801J0D01*
G01X1102763Y1197819D02*
G02X1102909Y1198172I500J0D01*
G01X1101463Y1196213D02*
Y1197819D01*
G01X1102763Y1196213D02*
Y1197819D01*
G01X1098826Y1190849D02*
Y1189143D01*
G01X1097526Y1190849D02*
Y1189143D01*
G01X1098972Y1191202D02*
G03X1098826Y1190849I354J-353D01*
G01X1098052Y1192121D02*
G03X1097526Y1190849I1275J-1272D01*
G01X1099473Y1191496D02*
G03X1099120Y1191350I0J-500D01*
G01X1099473Y1192796D02*
G03X1098201Y1192270I0J-1801D01*
G01X1136757Y1191496D02*
X1099473D01*
G01X1136900Y1192796D02*
X1099473D01*
G01X1097526Y1190849D02*
Y1189143D01*
G01X1098826Y1190849D02*
Y1189143D01*
G01X1098052Y1192121D02*
G03X1097526Y1190849I1275J-1272D01*
G01X1098972Y1191202D02*
G03X1098826Y1190849I354J-353D01*
G01X1099473Y1192796D02*
G03X1098201Y1192270I0J-1801D01*
G01X1099473Y1191496D02*
G03X1099120Y1191350I0J-500D01*
G01X1136900Y1192796D02*
X1099473D01*
G01X1136757Y1191496D02*
X1099473D01*
G01X1102763Y1183645D02*
Y1182039D01*
G01X1101463Y1183645D02*
Y1182039D01*
G01X1102909Y1183998D02*
G03X1102763Y1183645I354J-353D01*
G01X1101989Y1184917D02*
G03X1101463Y1183645I1275J-1272D01*
G01X1103174Y1184263D02*
X1102909Y1183998D01*
G01X1102255Y1185183D02*
X1101989Y1184917D01*
G01X1103527Y1184409D02*
G03X1103174Y1184263I0J-500D01*
G01X1103527Y1185709D02*
G03X1102255Y1185183I0J-1801D01*
G01X1135663Y1184409D02*
X1103527D01*
G01X1135759Y1185709D02*
X1103527D01*
G01X1144691Y1182406D02*
X1135663Y1184409D01*
G01X1145123Y1183642D02*
X1135851Y1185699D01*
G01X1101463Y1183645D02*
Y1182039D01*
G01X1102763Y1183645D02*
Y1182039D01*
G01X1101989Y1184917D02*
G03X1101463Y1183645I1275J-1272D01*
G01X1102909Y1183998D02*
G03X1102763Y1183645I354J-353D01*
G01X1102255Y1185183D02*
X1101989Y1184917D01*
G01X1103174Y1184263D02*
X1102909Y1183998D01*
G01X1103527Y1185709D02*
G03X1102255Y1185183I0J-1801D01*
G01X1103527Y1184409D02*
G03X1103174Y1184263I0J-500D01*
G01X1135759Y1185709D02*
X1103527D01*
G01X1135663Y1184409D02*
X1103527D01*
G01X1145123Y1183642D02*
X1135851Y1185699D01*
G01X1144691Y1182406D02*
X1135663Y1184409D01*
G01X1098826Y1275888D02*
Y1274182D01*
G01X1097526Y1275888D02*
Y1274182D01*
G01X1098972Y1276241D02*
G03X1098826Y1275888I354J-353D01*
G01X1098052Y1277160D02*
G03X1097526Y1275888I1275J-1272D01*
G01D02*
Y1274182D01*
G01X1098826Y1275888D02*
Y1274182D01*
G01X1098052Y1277160D02*
G03X1097526Y1275888I1275J-1272D01*
G01X1098972Y1276241D02*
G03X1098826Y1275888I354J-353D01*
G01X1134799Y1269449D02*
X1138526Y1268623D01*
G01X1134942Y1270749D02*
X1139031Y1269843D01*
G01X1103527Y1269449D02*
X1134799D01*
G01X1103527Y1270749D02*
X1134942D01*
G01X1103174Y1269303D02*
G02X1103527Y1269449I353J-354D01*
G01X1102255Y1270223D02*
G02X1103527Y1270749I1272J-1275D01*
G01X1102909Y1269038D02*
X1103174Y1269303D01*
G01X1101989Y1269957D02*
X1102255Y1270223D01*
G01X1102763Y1268685D02*
G02X1102909Y1269038I500J0D01*
G01X1101463Y1268685D02*
G02X1101989Y1269957I1801J0D01*
G01X1102763Y1267079D02*
Y1268685D01*
G01X1101463Y1267079D02*
Y1268685D01*
G01X1134942Y1270749D02*
X1139031Y1269843D01*
G01X1134799Y1269449D02*
X1138526Y1268623D01*
G01X1103527Y1270749D02*
X1134942D01*
G01X1103527Y1269449D02*
X1134799D01*
G01X1102255Y1270223D02*
G02X1103527Y1270749I1272J-1275D01*
G01X1103174Y1269303D02*
G02X1103527Y1269449I353J-354D01*
G01X1101989Y1269957D02*
X1102255Y1270223D01*
G01X1102909Y1269038D02*
X1103174Y1269303D01*
G01X1101463Y1268685D02*
G02X1101989Y1269957I1801J0D01*
G01X1102763Y1268685D02*
G02X1102909Y1269038I500J0D01*
G01X1101463Y1267079D02*
Y1268685D01*
G01X1102763Y1267079D02*
Y1268685D01*
G01X1098826Y1261715D02*
Y1260009D01*
G01X1097526Y1261715D02*
Y1260009D01*
G01X1098972Y1262068D02*
G03X1098826Y1261715I354J-353D01*
G01X1098052Y1262987D02*
G03X1097526Y1261715I1275J-1272D01*
G01X1099473Y1262362D02*
G03X1099120Y1262216I0J-500D01*
G01X1099473Y1263662D02*
G03X1098201Y1263136I0J-1801D01*
G01X1132718Y1262362D02*
X1099473D01*
G01X1132861Y1263662D02*
X1099473D01*
G01X1133633Y1263491D02*
X1132861Y1263662D01*
G01X1133984Y1262081D02*
X1132718Y1262362D01*
G01X1133633Y1263491D02*
X1132861Y1263662D01*
G01X1134266Y1263351D02*
X1133633Y1263491D01*
G01X1137782Y1261239D02*
X1133984Y1262081D01*
G01X1134266Y1263351D02*
X1133633Y1263491D01*
G01X1138287Y1262459D02*
X1134266Y1263351D01*
G01X1097526Y1261715D02*
Y1260009D01*
G01X1098826Y1261715D02*
Y1260009D01*
G01X1098052Y1262987D02*
G03X1097526Y1261715I1275J-1272D01*
G01X1098972Y1262068D02*
G03X1098826Y1261715I354J-353D01*
G01X1099473Y1263662D02*
G03X1098201Y1263136I0J-1801D01*
G01X1099473Y1262362D02*
G03X1099120Y1262216I0J-500D01*
G01X1132861Y1263662D02*
X1099473D01*
G01X1132718Y1262362D02*
X1099473D01*
G01X1133633Y1263491D02*
X1132861Y1263662D01*
G01X1132718Y1262362D02*
X1099473D01*
G01X1133984Y1262081D02*
X1132718Y1262362D01*
G01X1134266Y1263351D02*
X1133633Y1263491D01*
G01X1133984Y1262081D02*
X1132718Y1262362D01*
G01X1137782Y1261239D02*
X1133984Y1262081D01*
G01X1138287Y1262459D02*
X1134266Y1263351D01*
G01X1137782Y1261239D02*
X1133984Y1262081D01*
G01X1134666Y1255275D02*
X1138494Y1254427D01*
G01X1134809Y1256575D02*
X1138999Y1255647D01*
G01X1103527Y1255275D02*
X1134666D01*
G01X1103527Y1256575D02*
X1134809D01*
G01X1103174Y1255129D02*
G02X1103527Y1255275I353J-354D01*
G01X1102255Y1256049D02*
G02X1103527Y1256575I1272J-1275D01*
G01X1102909Y1254864D02*
X1103174Y1255129D01*
G01X1101989Y1255783D02*
X1102255Y1256049D01*
G01X1102763Y1254511D02*
G02X1102909Y1254864I500J0D01*
G01X1101463Y1254511D02*
G02X1101989Y1255783I1801J0D01*
G01X1102763Y1252905D02*
Y1254511D01*
G01X1101463Y1252905D02*
Y1254511D01*
G01X1134809Y1256575D02*
X1138999Y1255647D01*
G01X1134666Y1255275D02*
X1138494Y1254427D01*
G01X1103527Y1256575D02*
X1134809D01*
G01X1103527Y1255275D02*
X1134666D01*
G01X1102255Y1256049D02*
G02X1103527Y1256575I1272J-1275D01*
G01X1103174Y1255129D02*
G02X1103527Y1255275I353J-354D01*
G01X1101989Y1255783D02*
X1102255Y1256049D01*
G01X1102909Y1254864D02*
X1103174Y1255129D01*
G01X1101463Y1254511D02*
G02X1101989Y1255783I1801J0D01*
G01X1102763Y1254511D02*
G02X1102909Y1254864I500J0D01*
G01X1101463Y1252905D02*
Y1254511D01*
G01X1102763Y1252905D02*
Y1254511D01*
G01X1098826Y1247542D02*
Y1245836D01*
G01X1097526D02*
Y1247542D01*
G01X1098972Y1247895D02*
G03X1098826Y1247542I354J-353D01*
G01X1097526D02*
G02X1098052Y1248814I1801J0D01*
G01X1099473Y1248189D02*
G03X1099120Y1248043I0J-500D01*
G01X1098201Y1248963D02*
G02X1099473Y1249489I1272J-1275D01*
G01X1131752Y1248189D02*
X1099473D01*
G01Y1249489D02*
X1131895D01*
G01X1135333Y1247395D02*
X1131752Y1248189D01*
G01X1131895Y1249489D02*
X1135838Y1248615D01*
G01X1149311Y1238491D02*
X1135333Y1247395D01*
G01X1135838Y1248615D02*
X1150254Y1239433D01*
G01X1135838Y1248615D02*
X1150254Y1239433D01*
G01X1149311Y1238491D02*
X1135333Y1247395D01*
G01X1131895Y1249489D02*
X1135838Y1248615D01*
G01X1135333Y1247395D02*
X1131752Y1248189D01*
G01X1099473Y1249489D02*
X1131895D01*
G01X1131752Y1248189D02*
X1099473D01*
G01X1098201Y1248963D02*
G02X1099473Y1249489I1272J-1275D01*
G01Y1248189D02*
G03X1099120Y1248043I0J-500D01*
G01X1097526Y1247542D02*
G02X1098052Y1248814I1801J0D01*
G01X1098972Y1247895D02*
G03X1098826Y1247542I354J-353D01*
G01X1097526Y1245836D02*
Y1247542D01*
G01X1098826D02*
Y1245836D01*
G01X1102763Y1282858D02*
Y1281252D01*
G01X1101463Y1282858D02*
Y1281252D01*
G01X1102909Y1283211D02*
G03X1102763Y1282858I354J-353D01*
G01X1101989Y1284130D02*
G03X1101463Y1282858I1275J-1272D01*
G01X1103174Y1283476D02*
X1102909Y1283211D01*
G01X1102255Y1284396D02*
X1101989Y1284130D01*
G01X1103527Y1283622D02*
G03X1103174Y1283476I0J-500D01*
G01X1103527Y1284922D02*
G03X1102255Y1284396I0J-1801D01*
G01X1135195Y1283622D02*
X1103527D01*
G01X1135338Y1284922D02*
X1103527D01*
G01X1140014Y1282550D02*
X1135195Y1283622D01*
G01X1140520Y1283770D02*
X1135338Y1284922D01*
G01X1101463Y1282858D02*
Y1281252D01*
G01X1102763Y1282858D02*
Y1281252D01*
G01X1101989Y1284130D02*
G03X1101463Y1282858I1275J-1272D01*
G01X1102909Y1283211D02*
G03X1102763Y1282858I354J-353D01*
G01X1102255Y1284396D02*
X1101989Y1284130D01*
G01X1103174Y1283476D02*
X1102909Y1283211D01*
G01X1103527Y1284922D02*
G03X1102255Y1284396I0J-1801D01*
G01X1103527Y1283622D02*
G03X1103174Y1283476I0J-500D01*
G01X1135338Y1284922D02*
X1103527D01*
G01X1135195Y1283622D02*
X1103527D01*
G01X1140520Y1283770D02*
X1135338Y1284922D01*
G01X1140014Y1282550D02*
X1135195Y1283622D01*
G01X1099473Y1276535D02*
G03X1099120Y1276389I0J-500D01*
G01X1099473Y1277835D02*
G03X1098201Y1277309I0J-1801D01*
G01X1135291Y1276535D02*
X1099473D01*
G01X1135434Y1277835D02*
X1099473D01*
G01X1136399Y1276288D02*
X1135291Y1276534D01*
G01X1138012Y1277263D02*
X1135434Y1277835D01*
G01X1138012Y1277263D02*
X1135434Y1277835D01*
G01X1099473D02*
G03X1098201Y1277309I0J-1801D01*
G01X1099473Y1276535D02*
G03X1099120Y1276389I0J-500D01*
G01X1135434Y1277835D02*
X1099473D01*
G01X1135291Y1276535D02*
X1099473D01*
G01X1138012Y1277263D02*
X1135434Y1277835D01*
G01X1136399Y1276288D02*
X1135291Y1276534D01*
G01X1102763Y1353724D02*
Y1352118D01*
G01X1101463Y1353724D02*
Y1352118D01*
G01X1102909Y1354077D02*
G03X1102763Y1353724I354J-353D01*
G01X1101989Y1354996D02*
G03X1101463Y1353724I1275J-1272D01*
G01X1103174Y1354342D02*
X1102909Y1354077D01*
G01X1102255Y1355262D02*
X1101989Y1354996D01*
G01X1103527Y1354488D02*
G03X1103174Y1354342I0J-500D01*
G01X1103527Y1355788D02*
G03X1102255Y1355262I0J-1801D01*
G01X1137300Y1354488D02*
X1103527D01*
G01X1137550Y1355788D02*
X1103527D01*
G01X1101463Y1353724D02*
Y1352118D01*
G01X1102763Y1353724D02*
Y1352118D01*
G01X1101989Y1354996D02*
G03X1101463Y1353724I1275J-1272D01*
G01X1102909Y1354077D02*
G03X1102763Y1353724I354J-353D01*
G01X1102255Y1355262D02*
X1101989Y1354996D01*
G01X1103174Y1354342D02*
X1102909Y1354077D01*
G01X1103527Y1355788D02*
G03X1102255Y1355262I0J-1801D01*
G01X1103527Y1354488D02*
G03X1103174Y1354342I0J-500D01*
G01X1137550Y1355788D02*
X1103527D01*
G01X1137300Y1354488D02*
X1103527D01*
G01X1133998Y1348701D02*
X1142361Y1346849D01*
G01X1133855Y1347401D02*
X1137855Y1346515D01*
G01X1133998Y1348701D02*
X1142361Y1346849D01*
G01X1099473Y1347401D02*
X1133855D01*
G01X1099473Y1348701D02*
X1133998D01*
G01X1099120Y1347255D02*
G02X1099473Y1347401I353J-354D01*
G01X1098201Y1348175D02*
G02X1099473Y1348701I1272J-1275D01*
G01X1098826Y1346754D02*
G02X1098972Y1347107I500J0D01*
G01X1097526Y1346754D02*
G02X1098052Y1348026I1801J0D01*
G01X1098826Y1345048D02*
Y1346754D01*
G01X1097526Y1345048D02*
Y1346754D01*
G01X1133998Y1348701D02*
X1142361Y1346849D01*
G01X1133855Y1347401D02*
X1137855Y1346515D01*
G01X1099473Y1348701D02*
X1133998D01*
G01X1099473Y1347401D02*
X1133855D01*
G01X1098201Y1348175D02*
G02X1099473Y1348701I1272J-1275D01*
G01X1099120Y1347255D02*
G02X1099473Y1347401I353J-354D01*
G01X1097526Y1346754D02*
G02X1098052Y1348026I1801J0D01*
G01X1098826Y1346754D02*
G02X1098972Y1347107I500J0D01*
G01X1097526Y1345048D02*
Y1346754D01*
G01X1098826Y1345048D02*
Y1346754D01*
G01X1135322Y1340315D02*
X1140258Y1339221D01*
G01X1135465Y1341615D02*
X1140763Y1340441D01*
G01X1103527Y1340315D02*
X1135322D01*
G01X1103527Y1341615D02*
X1135465D01*
G01X1103174Y1340169D02*
G02X1103527Y1340315I353J-354D01*
G01X1102255Y1341089D02*
G02X1103527Y1341615I1272J-1275D01*
G01X1102909Y1339904D02*
X1103174Y1340169D01*
G01X1101989Y1340823D02*
X1102255Y1341089D01*
G01X1102763Y1339551D02*
G02X1102909Y1339904I500J0D01*
G01X1101463Y1339551D02*
G02X1101989Y1340823I1801J0D01*
G01X1102763Y1337945D02*
Y1339551D01*
G01X1101463Y1337945D02*
Y1339551D01*
G01X1135465Y1341615D02*
X1140763Y1340441D01*
G01X1135322Y1340315D02*
X1140258Y1339221D01*
G01X1103527Y1341615D02*
X1135465D01*
G01X1103527Y1340315D02*
X1135322D01*
G01X1102255Y1341089D02*
G02X1103527Y1341615I1272J-1275D01*
G01X1103174Y1340169D02*
G02X1103527Y1340315I353J-354D01*
G01X1101989Y1340823D02*
X1102255Y1341089D01*
G01X1102909Y1339904D02*
X1103174Y1340169D01*
G01X1101463Y1339551D02*
G02X1101989Y1340823I1801J0D01*
G01X1102763Y1339551D02*
G02X1102909Y1339904I500J0D01*
G01X1101463Y1337945D02*
Y1339551D01*
G01X1102763Y1337945D02*
Y1339551D01*
G01X1098826Y1332581D02*
Y1330875D01*
G01X1097526D02*
Y1332581D01*
G01X1098972Y1332934D02*
G03X1098826Y1332581I354J-353D01*
G01X1097526D02*
G02X1098052Y1333853I1801J0D01*
G01X1099473Y1333228D02*
G03X1099120Y1333082I0J-500D01*
G01X1098201Y1334002D02*
G02X1099473Y1334528I1272J-1275D01*
G01X1132013Y1333228D02*
X1099473D01*
G01Y1334528D02*
X1132156D01*
G01X1135063Y1332552D02*
X1132013Y1333228D01*
G01X1132156Y1334528D02*
X1135568Y1333772D01*
G01X1150829Y1322508D02*
X1135063Y1332552D01*
G01X1135568Y1333772D02*
X1151771Y1323450D01*
G01X1135568Y1333772D02*
X1151771Y1323450D01*
G01X1150829Y1322508D02*
X1135063Y1332552D01*
G01X1132156Y1334528D02*
X1135568Y1333772D01*
G01X1135063Y1332552D02*
X1132013Y1333228D01*
G01X1099473Y1334528D02*
X1132156D01*
G01X1132013Y1333228D02*
X1099473D01*
G01X1098201Y1334002D02*
G02X1099473Y1334528I1272J-1275D01*
G01Y1333228D02*
G03X1099120Y1333082I0J-500D01*
G01X1097526Y1332581D02*
G02X1098052Y1333853I1801J0D01*
G01X1098972Y1332934D02*
G03X1098826Y1332581I354J-353D01*
G01X1097526Y1330875D02*
Y1332581D01*
G01X1098826D02*
Y1330875D01*
G01X1102763Y1367897D02*
Y1366291D01*
G01X1101463Y1367897D02*
Y1366291D01*
G01X1102909Y1368250D02*
G03X1102763Y1367897I354J-353D01*
G01X1101989Y1369169D02*
G03X1101463Y1367897I1275J-1272D01*
G01X1103174Y1368515D02*
X1102909Y1368250D01*
G01X1102255Y1369435D02*
X1101989Y1369169D01*
G01X1103527Y1368661D02*
G03X1103174Y1368515I0J-500D01*
G01X1103527Y1369961D02*
G03X1102255Y1369435I0J-1801D01*
G01X1135003Y1368661D02*
X1103527D01*
G01X1135099Y1369961D02*
X1103527D01*
G01X1398220Y1310311D02*
X1135003Y1368661D01*
G01X1365599Y1318876D02*
X1135191Y1369951D01*
G01X1101463Y1367897D02*
Y1366291D01*
G01X1102763Y1367897D02*
Y1366291D01*
G01X1101989Y1369169D02*
G03X1101463Y1367897I1275J-1272D01*
G01X1102909Y1368250D02*
G03X1102763Y1367897I354J-353D01*
G01X1102255Y1369435D02*
X1101989Y1369169D01*
G01X1103174Y1368515D02*
X1102909Y1368250D01*
G01X1103527Y1369961D02*
G03X1102255Y1369435I0J-1801D01*
G01X1103527Y1368661D02*
G03X1103174Y1368515I0J-500D01*
G01X1135099Y1369961D02*
X1103527D01*
G01X1135003Y1368661D02*
X1103527D01*
G01X1365599Y1318876D02*
X1135191Y1369951D01*
G01X1398220Y1310311D02*
X1135003Y1368661D01*
G01X1398220Y1310311D02*
X1135003Y1368661D01*
G01X1098826Y1360928D02*
Y1359222D01*
G01X1097526Y1360928D02*
Y1359222D01*
G01X1098972Y1361281D02*
G03X1098826Y1360928I354J-353D01*
G01X1098052Y1362200D02*
G03X1097526Y1360928I1275J-1272D01*
G01X1099473Y1361575D02*
G03X1099120Y1361429I0J-500D01*
G01X1099473Y1362875D02*
G03X1098201Y1362349I0J-1801D01*
G01X1139681Y1361575D02*
X1099473D01*
G01X1139824Y1362875D02*
X1099473D01*
G01X1097526Y1360928D02*
Y1359222D01*
G01X1098826Y1360928D02*
Y1359222D01*
G01X1098052Y1362200D02*
G03X1097526Y1360928I1275J-1272D01*
G01X1098972Y1361281D02*
G03X1098826Y1360928I354J-353D01*
G01X1099473Y1362875D02*
G03X1098201Y1362349I0J-1801D01*
G01X1099473Y1361575D02*
G03X1099120Y1361429I0J-500D01*
G01X1139824Y1362875D02*
X1099473D01*
G01X1139681Y1361575D02*
X1099473D01*
G01X1184518Y804275D02*
X1219602Y962558D01*
G01X1223424Y628738D02*
X1184518Y804275D01*
G01D02*
X1219602Y962558D01*
G01X1223424Y628738D02*
X1184518Y804275D01*
G01X1186292Y1120000D02*
X1153894Y1168949D01*
G01X1186292Y1120000D02*
X1153894Y1168949D01*
G01X1186292Y1120000D02*
X1153894Y1168949D01*
G01X1186292Y1120000D02*
X1153894Y1168949D01*
G01X1185074Y1119484D02*
X1165927Y1148412D01*
G01X1186292Y1120000D02*
X1153894Y1168949D01*
G01X1186292Y1120000D02*
X1153894Y1168949D01*
G01X1185074Y1119484D02*
X1165927Y1148412D01*
G01X1175900Y1171416D02*
X1198918Y1136641D01*
G01X1169878Y1182871D02*
X1200135Y1137158D01*
G01X1173582Y1174918D02*
X1174286Y1173855D01*
G01X1169878Y1182871D02*
X1200135Y1137158D01*
G01X1171264Y1178421D02*
X1171968Y1177357D01*
G01X1169878Y1182871D02*
X1200135Y1137158D01*
G01X1169878Y1182871D02*
X1200135Y1137158D01*
G01X1169878Y1182871D02*
X1200135Y1137158D01*
G01X1175900Y1171416D02*
X1198918Y1136641D01*
G01X1173582Y1174918D02*
X1174286Y1173855D01*
G01X1171264Y1178421D02*
X1171968Y1177357D01*
G01X1164051Y1179005D02*
X1145356Y1190921D01*
G01X1161556Y1179053D02*
X1153984Y1183879D01*
G01X1164051Y1179005D02*
X1145356Y1190921D01*
G01X1163119Y1178057D02*
X1161556Y1179053D01*
G01X1164051Y1179005D02*
X1145356Y1190921D01*
G01X1163823Y1176994D02*
X1163119Y1178057D01*
G01X1194225Y1133417D02*
X1164051Y1179005D01*
G01X1166141Y1173491D02*
X1165437Y1174555D01*
G01X1194225Y1133417D02*
X1164051Y1179005D01*
G01X1168459Y1169989D02*
X1167755Y1171052D01*
G01X1194225Y1133417D02*
X1164051Y1179005D01*
G01X1193008Y1132900D02*
X1170073Y1167550D01*
G01X1194225Y1133417D02*
X1164051Y1179005D01*
G01D02*
X1145356Y1190921D01*
G01X1161556Y1179053D02*
X1153984Y1183879D01*
G01X1163119Y1178057D02*
X1161556Y1179053D01*
G01X1194225Y1133417D02*
X1164051Y1179005D01*
G01X1163823Y1176994D02*
X1163119Y1178057D01*
G01X1166141Y1173491D02*
X1165437Y1174555D01*
G01X1168459Y1169989D02*
X1167755Y1171052D01*
G01X1193008Y1132900D02*
X1170073Y1167550D01*
G01X1156560Y1174846D02*
X1144691Y1182406D01*
G01X1156964Y1176131D02*
X1151324Y1179723D01*
G01X1157492Y1175794D02*
X1156964Y1176131D01*
G01X1157570Y1173320D02*
X1156560Y1174846D01*
G01X1189486Y1127456D02*
X1157492Y1175794D01*
G01X1159888Y1169818D02*
X1159184Y1170881D01*
G01X1189486Y1127456D02*
X1157492Y1175794D01*
G01X1162206Y1166316D02*
X1161502Y1167379D01*
G01X1189486Y1127456D02*
X1157492Y1175794D01*
G01X1188269Y1126939D02*
X1163821Y1163876D01*
G01X1189486Y1127456D02*
X1157492Y1175794D01*
G01X1156560Y1174846D02*
X1144691Y1182406D01*
G01X1156964Y1176131D02*
X1151324Y1179723D01*
G01X1156560Y1174846D02*
X1144691Y1182406D01*
G01X1157492Y1175794D02*
X1156964Y1176131D01*
G01X1156560Y1174846D02*
X1144691Y1182406D01*
G01X1189486Y1127456D02*
X1157492Y1175794D01*
G01X1157570Y1173320D02*
X1156560Y1174846D01*
G01X1159888Y1169818D02*
X1159184Y1170881D01*
G01X1162206Y1166316D02*
X1161502Y1167379D01*
G01X1188269Y1126939D02*
X1163821Y1163876D01*
G01X1141379Y1176921D02*
X1136800Y1177935D01*
G01X1152962Y1168001D02*
X1140874Y1175701D01*
G01X1153894Y1168949D02*
X1141379Y1176921D01*
G01X1153666Y1166938D02*
X1152962Y1168001D01*
G01X1155984Y1163435D02*
X1155280Y1164499D01*
G01X1158302Y1159933D02*
X1157598Y1160996D01*
G01X1165927Y1148412D02*
X1159916Y1157494D01*
G01X1141379Y1176921D02*
X1136800Y1177935D01*
G01X1153894Y1168949D02*
X1141379Y1176921D01*
G01X1152962Y1168001D02*
X1140874Y1175701D01*
G01X1153666Y1166938D02*
X1152962Y1168001D01*
G01X1155984Y1163435D02*
X1155280Y1164499D01*
G01X1158302Y1159933D02*
X1157598Y1160996D01*
G01X1165927Y1148412D02*
X1159916Y1157494D01*
G01X1170530Y1241919D02*
X1215781Y1170894D01*
G01X1164702Y1253488D02*
X1217001Y1171399D01*
G01X1164702Y1253488D02*
X1217001Y1171399D01*
G01X1164702Y1253488D02*
X1217001Y1171399D01*
G01X1164702Y1253488D02*
X1217001Y1171399D01*
G01X1164702Y1253488D02*
X1217001Y1171399D01*
G01X1170530Y1241919D02*
X1215781Y1170894D01*
G01X1211676Y1167488D02*
X1159961Y1248649D01*
G01X1211676Y1167488D02*
X1159961Y1248649D01*
G01X1211676Y1167488D02*
X1159961Y1248649D01*
G01X1210456Y1166983D02*
X1166046Y1236679D01*
G01X1211676Y1167488D02*
X1159961Y1248649D01*
G01X1211676Y1167488D02*
X1159961Y1248649D01*
G01X1210456Y1166983D02*
X1166046Y1236679D01*
G01X1159131Y1234969D02*
X1205726Y1161840D01*
G01X1153302Y1246537D02*
X1206946Y1162345D01*
G01X1153302Y1246537D02*
X1206946Y1162345D01*
G01X1153302Y1246537D02*
X1206946Y1162345D01*
G01X1153302Y1246537D02*
X1206946Y1162345D01*
G01X1153302Y1246537D02*
X1206946Y1162345D01*
G01X1159131Y1234969D02*
X1205726Y1161840D01*
G01X1150254Y1239433D02*
X1202761Y1156904D01*
G01X1156861Y1226624D02*
X1156177Y1227700D01*
G01X1150254Y1239433D02*
X1202761Y1156904D01*
G01X1159116Y1223080D02*
X1158431Y1224156D01*
G01X1150254Y1239433D02*
X1202761Y1156904D01*
G01X1201541Y1156399D02*
X1160686Y1220613D01*
G01X1150254Y1239433D02*
X1202761Y1156904D01*
G01X1150254Y1239433D02*
X1202761Y1156904D01*
G01X1156861Y1226624D02*
X1156177Y1227700D01*
G01X1159116Y1223080D02*
X1158431Y1224156D01*
G01X1201541Y1156399D02*
X1160686Y1220613D01*
G01X1168946Y1181923D02*
X1169650Y1180860D01*
G01X1145815Y1196661D02*
X1168946Y1181923D01*
G01X1146321Y1197881D02*
X1169878Y1182871D01*
G01X1137155Y1198583D02*
X1145815Y1196661D01*
G01X1137298Y1199883D02*
X1146321Y1197881D01*
G01X1168946Y1181923D02*
X1169650Y1180860D01*
G01X1146321Y1197881D02*
X1169878Y1182871D01*
G01X1145815Y1196661D02*
X1168946Y1181923D01*
G01X1137298Y1199883D02*
X1146321Y1197881D01*
G01X1137155Y1198583D02*
X1145815Y1196661D01*
G01X1144851Y1189701D02*
X1136757Y1191496D01*
G01X1145356Y1190921D02*
X1136900Y1192796D01*
G01X1153984Y1183879D02*
X1144851Y1189701D01*
G01X1145356Y1190921D02*
X1136900Y1192796D01*
G01X1144851Y1189701D02*
X1136757Y1191496D01*
G01X1153984Y1183879D02*
X1144851Y1189701D01*
G01X1151324Y1179723D02*
X1145259Y1183586D01*
G01X1151324Y1179723D02*
X1145259Y1183586D01*
G01X1151771Y1323450D02*
X1230283Y1200211D01*
G01X1151771Y1323450D02*
X1230283Y1200211D01*
G01X1151771Y1323450D02*
X1230283Y1200211D01*
G01X1229063Y1199706D02*
X1160405Y1307477D01*
G01X1151771Y1323450D02*
X1230283Y1200211D01*
G01X1151771Y1323450D02*
X1230283Y1200211D01*
G01X1229063Y1199706D02*
X1160405Y1307477D01*
G01X1175586Y1259890D02*
X1140014Y1282550D01*
G01X1176528Y1260832D02*
X1140520Y1283770D01*
G01X1176271Y1258815D02*
X1175586Y1259890D01*
G01X1230127Y1176696D02*
X1176528Y1260832D01*
G01X1178528Y1255272D02*
X1177843Y1256348D01*
G01X1230127Y1176696D02*
X1176528Y1260832D01*
G01X1180784Y1251730D02*
X1180099Y1252805D01*
G01X1230127Y1176696D02*
X1176528Y1260832D01*
G01X1228907Y1176191D02*
X1182356Y1249263D01*
G01X1230127Y1176696D02*
X1176528Y1260832D01*
G01D02*
X1140520Y1283770D01*
G01X1175586Y1259890D02*
X1140014Y1282550D01*
G01X1230127Y1176696D02*
X1176528Y1260832D01*
G01X1176271Y1258815D02*
X1175586Y1259890D01*
G01X1178528Y1255272D02*
X1177843Y1256348D01*
G01X1180784Y1251730D02*
X1180099Y1252805D01*
G01X1228907Y1176191D02*
X1182356Y1249263D01*
G01X1137507Y1276043D02*
X1136399Y1276288D01*
G01X1169315Y1255775D02*
X1137507Y1276043D01*
G01X1170257Y1256717D02*
X1138012Y1277263D01*
G01X1170000Y1254700D02*
X1169315Y1255775D01*
G01X1221396Y1176434D02*
X1170257Y1256717D01*
G01X1172256Y1251157D02*
X1171571Y1252233D01*
G01X1221396Y1176434D02*
X1170257Y1256717D01*
G01X1174513Y1247615D02*
X1173828Y1248690D01*
G01X1221396Y1176434D02*
X1170257Y1256717D01*
G01X1220176Y1175929D02*
X1176084Y1245148D01*
G01X1221396Y1176434D02*
X1170257Y1256717D01*
G01X1137507Y1276043D02*
X1136399Y1276288D01*
G01X1170257Y1256717D02*
X1138012Y1277263D01*
G01X1169315Y1255775D02*
X1137507Y1276043D01*
G01X1221396Y1176434D02*
X1170257Y1256717D01*
G01X1170000Y1254700D02*
X1169315Y1255775D01*
G01X1172256Y1251157D02*
X1171571Y1252233D01*
G01X1174513Y1247615D02*
X1173828Y1248690D01*
G01X1220176Y1175929D02*
X1176084Y1245148D01*
G01X1168273Y1245462D02*
X1168959Y1244386D01*
G01X1166017Y1249004D02*
X1166702Y1247928D01*
G01X1163760Y1252546D02*
X1164445Y1251471D01*
G01X1138526Y1268623D02*
X1163760Y1252546D01*
G01X1139031Y1269843D02*
X1164702Y1253488D01*
G01X1168273Y1245462D02*
X1168959Y1244386D01*
G01X1166017Y1249004D02*
X1166702Y1247928D01*
G01X1163760Y1252546D02*
X1164445Y1251471D01*
G01X1139031Y1269843D02*
X1164702Y1253488D01*
G01X1138526Y1268623D02*
X1163760Y1252546D01*
G01X1159019Y1247707D02*
X1137782Y1261239D01*
G01X1159961Y1248649D02*
X1138287Y1262459D01*
G01X1159960Y1246230D02*
X1159019Y1247707D01*
G01X1162217Y1242688D02*
X1161532Y1243763D01*
G01X1164474Y1239146D02*
X1163789Y1240221D01*
G01X1159961Y1248649D02*
X1138287Y1262459D01*
G01X1159019Y1247707D02*
X1137782Y1261239D01*
G01X1159960Y1246230D02*
X1159019Y1247707D01*
G01X1162217Y1242688D02*
X1161532Y1243763D01*
G01X1164474Y1239146D02*
X1163789Y1240221D01*
G01X1156874Y1238511D02*
X1157559Y1237436D01*
G01X1154617Y1242053D02*
X1155302Y1240978D01*
G01X1152360Y1245595D02*
X1153045Y1244520D01*
G01X1138494Y1254427D02*
X1152360Y1245595D01*
G01X1138999Y1255647D02*
X1153302Y1246537D01*
G01X1156874Y1238511D02*
X1157559Y1237436D01*
G01X1154617Y1242053D02*
X1155302Y1240978D01*
G01X1152360Y1245595D02*
X1153045Y1244520D01*
G01X1138999Y1255647D02*
X1153302Y1246537D01*
G01X1138494Y1254427D02*
X1152360Y1245595D01*
G01X1154607Y1230168D02*
X1149311Y1238491D01*
G01X1154607Y1230168D02*
X1149311Y1238491D01*
G01X1177365Y1324549D02*
X1207049Y1277957D01*
G01X1184481Y1310958D02*
X1191262Y1300315D01*
G01X1177365Y1324549D02*
X1207049Y1277957D01*
G01X1182225Y1314500D02*
X1182910Y1313425D01*
G01X1177365Y1324549D02*
X1207049Y1277957D01*
G01X1179968Y1318043D02*
X1180653Y1316967D01*
G01X1177365Y1324549D02*
X1207049Y1277957D01*
G01X1176423Y1323607D02*
X1178396Y1320510D01*
G01X1177365Y1324549D02*
X1207049Y1277957D01*
G01X1141856Y1345629D02*
X1176423Y1323607D01*
G01X1142361Y1346849D02*
X1177365Y1324549D01*
G01D02*
X1207049Y1277957D01*
G01X1184481Y1310958D02*
X1191262Y1300315D01*
G01X1182225Y1314500D02*
X1182910Y1313425D01*
G01X1179968Y1318043D02*
X1180653Y1316967D01*
G01X1176423Y1323607D02*
X1178396Y1320510D01*
G01X1142361Y1346849D02*
X1177365Y1324549D01*
G01X1141856Y1345629D02*
X1176423Y1323607D01*
G01X1179040Y1306687D02*
X1297329Y1121004D01*
G01X1171590Y1320801D02*
X1298296Y1121908D01*
G01X1176783Y1310229D02*
X1177468Y1309154D01*
G01X1171590Y1320801D02*
X1298296Y1121908D01*
G01X1174526Y1313771D02*
X1175211Y1312696D01*
G01X1171590Y1320801D02*
X1298296Y1121908D01*
G01X1170648Y1319859D02*
X1172955Y1316238D01*
G01X1171590Y1320801D02*
X1298296Y1121908D01*
G01X1140258Y1339221D02*
X1170648Y1319859D01*
G01X1140763Y1340441D02*
X1171590Y1320801D01*
G01D02*
X1298296Y1121908D01*
G01X1179040Y1306687D02*
X1297329Y1121004D01*
G01X1176783Y1310229D02*
X1177468Y1309154D01*
G01X1174526Y1313771D02*
X1175211Y1312696D01*
G01X1170648Y1319859D02*
X1172955Y1316238D01*
G01X1140763Y1340441D02*
X1171590Y1320801D01*
G01X1140258Y1339221D02*
X1170648Y1319859D01*
G01X1154320Y1317029D02*
X1150829Y1322508D01*
G01X1156576Y1313486D02*
X1155891Y1314562D01*
G01X1158833Y1309944D02*
X1158148Y1311019D01*
G01X1154320Y1317029D02*
X1150829Y1322508D01*
G01X1156576Y1313486D02*
X1155891Y1314562D01*
G01X1158833Y1309944D02*
X1158148Y1311019D01*
G01X1140836Y1353704D02*
X1137300Y1354487D01*
G01X1141341Y1354924D02*
X1137581Y1355757D01*
G01X1168257Y1336235D02*
X1140836Y1353704D01*
G01X1168956Y1337332D02*
X1141341Y1354924D01*
G01X1184676Y1325776D02*
X1168257Y1336235D01*
G01X1185618Y1326718D02*
X1168956Y1337332D01*
G01X1141341Y1354924D02*
X1137581Y1355757D01*
G01X1140836Y1353704D02*
X1137300Y1354487D01*
G01X1168956Y1337332D02*
X1141341Y1354924D01*
G01X1168257Y1336235D02*
X1140836Y1353704D01*
G01X1185618Y1326718D02*
X1168956Y1337332D01*
G01X1184676Y1325776D02*
X1168257Y1336235D01*
G01X1137855Y1346515D02*
X1141856Y1345629D01*
G01X1137855Y1346515D02*
X1141856Y1345629D01*
G01X1400858Y1303669D02*
X1139681Y1361575D01*
G01X1419989Y1300760D02*
X1139824Y1362875D01*
G01X1419989Y1300760D02*
X1139824Y1362875D01*
G01X1419989Y1300760D02*
X1139824Y1362875D01*
G01X1419989Y1300760D02*
X1139824Y1362875D01*
G01X1419989Y1300760D02*
X1139824Y1362875D01*
G01X1400858Y1303669D02*
X1139681Y1361575D01*
G01X1231425Y626727D02*
X1190462Y811514D01*
G01X1232642Y627253D02*
X1191794Y811514D01*
G01X1469083Y281132D02*
X1231425Y626727D01*
G01X1470047Y282026D02*
X1232642Y627253D01*
G01D02*
X1191794Y811514D01*
G01X1231425Y626727D02*
X1190462Y811514D01*
G01X1470047Y282026D02*
X1232642Y627253D01*
G01X1469083Y281132D02*
X1231425Y626727D01*
G01X1224639Y629267D02*
X1185850Y804276D01*
G01X1474351Y263866D02*
X1223424Y628738D01*
G01X1475495Y264497D02*
X1224639Y629267D01*
G01D02*
X1185850Y804276D01*
G01X1475495Y264497D02*
X1224639Y629267D01*
G01X1474351Y263866D02*
X1223424Y628738D01*
G01X1205381Y807891D02*
X1244752Y630285D01*
G01X1206713Y807891D02*
X1245967Y630814D01*
G01X1206713Y807891D02*
X1245967Y630814D01*
G01X1205381Y807891D02*
X1244752Y630285D01*
G01X1238960Y626341D02*
X1197290Y814290D01*
G01X1238974Y632288D02*
X1198622Y814290D01*
G01X1238974Y632288D02*
X1198622Y814290D01*
G01X1238960Y626341D02*
X1197290Y814290D01*
G01X1238960Y626341D02*
X1197290Y814290D01*
G01X1213577Y809491D02*
X1253089Y631277D01*
G01X1251868Y630774D02*
X1217246Y786932D01*
G01X1213577Y809491D02*
X1253089Y631277D01*
G01X1213577Y809491D02*
X1253089Y631277D01*
G01X1251868Y630774D02*
X1217246Y786932D01*
G01X1217247D02*
X1212245Y809491D01*
G01X1217247Y786932D02*
X1212245Y809491D01*
G01X1246718Y958965D02*
X1213577Y809491D01*
G01X1212245D02*
X1228878Y884509D01*
G01X1246718Y958965D02*
X1213577Y809491D01*
G01X1246718Y958965D02*
X1213577Y809491D01*
G01X1212245D02*
X1228878Y884509D01*
G01X1238586Y957704D02*
X1205381Y807891D01*
G01X1239918Y957704D02*
X1206713Y807891D01*
G01X1239918Y957704D02*
X1206713Y807891D01*
G01X1238586Y957704D02*
X1205381Y807891D01*
G01X1197290Y814290D02*
X1230468Y963959D01*
G01X1198622Y814290D02*
X1231800Y963959D01*
G01X1198622Y814290D02*
X1231800Y963959D01*
G01X1197290Y814290D02*
X1230468Y963959D01*
G01X1190462Y811514D02*
X1224339Y964295D01*
G01X1191794Y811514D02*
X1225671Y964295D01*
G01X1191794Y811514D02*
X1225671Y964295D01*
G01X1190462Y811514D02*
X1224339Y964295D01*
G01X1185850Y804276D02*
X1220934Y962557D01*
G01X1185850Y804276D02*
X1220934Y962557D01*
G01X1228878Y884509D02*
X1245386Y958965D01*
G01X1228878Y884509D02*
X1245386Y958965D01*
G01X1218751Y1047173D02*
X1238586Y957704D01*
G01X1218751Y1047173D02*
X1238586Y957704D01*
G01X1230468Y963959D02*
X1193008Y1132900D01*
G01X1231800Y963959D02*
X1194225Y1133417D01*
G01X1231800Y963959D02*
X1194225Y1133417D01*
G01X1230468Y963959D02*
X1193008Y1132900D01*
G01X1224339Y964295D02*
X1205072Y1051166D01*
G01X1225671Y964295D02*
X1206342Y1051448D01*
G01X1225671Y964295D02*
X1206342Y1051448D01*
G01X1224339Y964295D02*
X1205072Y1051166D01*
G01X1219602Y962558D02*
X1185074Y1119484D01*
G01X1220934Y962557D02*
X1186292Y1120000D01*
G01X1220934Y962557D02*
X1186292Y1120000D01*
G01X1219602Y962558D02*
X1185074Y1119484D01*
G01X1245386Y958965D02*
X1201541Y1156399D01*
G01X1202761Y1156904D02*
X1246718Y958965D01*
G01X1202761Y1156904D02*
X1246718Y958965D01*
G01X1245386D02*
X1201541Y1156399D01*
G01X1229938Y1002720D02*
X1239918Y957704D01*
G01X1200135Y1137158D02*
X1229938Y1002720D01*
G01D02*
X1239918Y957704D01*
G01X1200135Y1137158D02*
X1229938Y1002720D01*
G01X1234840Y1056963D02*
X1210456Y1166983D01*
G01X1236062Y1057463D02*
X1211676Y1167488D01*
G01X1236062Y1057463D02*
X1211676Y1167488D01*
G01X1234840Y1056963D02*
X1210456Y1166983D01*
G01X1230068Y1052054D02*
X1238255Y1015132D01*
G01X1206946Y1162345D02*
X1239475Y1015637D01*
G01X1221940Y1088710D02*
X1230068Y1052054D01*
G01X1206946Y1162345D02*
X1239475Y1015637D01*
G01X1206946Y1162345D02*
X1239475Y1015637D01*
G01X1206946Y1162345D02*
X1239475Y1015637D01*
G01X1230068Y1052054D02*
X1238255Y1015132D01*
G01X1221940Y1088710D02*
X1230068Y1052054D01*
G01X1198918Y1136641D02*
X1218751Y1047173D01*
G01X1198918Y1136641D02*
X1218751Y1047173D01*
G01X1205072Y1051166D02*
X1188269Y1126939D01*
G01X1206342Y1051448D02*
X1197940Y1089334D01*
G01X1205072Y1051166D02*
X1188269Y1126939D01*
G01X1206342Y1051448D02*
X1197940Y1089334D01*
G01X1205072Y1051166D02*
X1188269Y1126939D01*
G01X1242931Y1073239D02*
X1220176Y1175929D01*
G01X1244151Y1073744D02*
X1221396Y1176434D01*
G01X1244151Y1073744D02*
X1221396Y1176434D01*
G01X1242931Y1073239D02*
X1220176Y1175929D01*
G01X1215781Y1170894D02*
X1235537Y1081788D01*
G01X1217001Y1171399D02*
X1236807Y1082071D01*
G01X1217001Y1171399D02*
X1236807Y1082071D01*
G01X1215781Y1170894D02*
X1235537Y1081788D01*
G01X1205726Y1161840D02*
X1221940Y1088710D01*
G01X1205726Y1161840D02*
X1221940Y1088710D01*
G01X1197940Y1089334D02*
X1189486Y1127456D01*
G01X1197940Y1089334D02*
X1189486Y1127456D01*
G01X1251120Y1075998D02*
X1228907Y1176191D01*
G01X1252339Y1076508D02*
X1230127Y1176696D01*
G01X1252339Y1076508D02*
X1230127Y1176696D01*
G01X1251120Y1075998D02*
X1228907Y1176191D01*
G01X1255843Y1078904D02*
X1229063Y1199706D01*
G01X1230283Y1200211D02*
X1257014Y1079632D01*
G01X1230283Y1200211D02*
X1257014Y1079632D01*
G01X1255843Y1078904D02*
X1229063Y1199706D01*
G01X1319357Y1218961D02*
X1207207Y1290408D01*
G01X1319862Y1220181D02*
X1208149Y1291350D01*
G01X1319862Y1220181D02*
X1208149Y1291350D01*
G01X1319357Y1218961D02*
X1207207Y1290408D01*
G01X1206103Y1277020D02*
X1275960Y1231580D01*
G01X1207049Y1277957D02*
X1276886Y1232530D01*
G01X1207049Y1277957D02*
X1276886Y1232530D01*
G01X1206103Y1277020D02*
X1275960Y1231580D01*
G01X1208149Y1291350D02*
X1185618Y1326718D01*
G01X1187618Y1321158D02*
X1186933Y1322234D01*
G01X1208149Y1291350D02*
X1185618Y1326718D01*
G01X1189874Y1317616D02*
X1189189Y1318691D01*
G01X1208149Y1291350D02*
X1185618Y1326718D01*
G01X1199087Y1303155D02*
X1191446Y1315149D01*
G01X1208149Y1291350D02*
X1185618Y1326718D01*
G01X1207207Y1290408D02*
X1199087Y1303155D01*
G01X1208149Y1291350D02*
X1185618Y1326718D01*
G01X1208149Y1291350D02*
X1185618Y1326718D01*
G01X1187618Y1321158D02*
X1186933Y1322234D01*
G01X1189874Y1317616D02*
X1189189Y1318691D01*
G01X1199087Y1303155D02*
X1191446Y1315149D01*
G01X1207207Y1290408D02*
X1199087Y1303155D01*
G01X1191262Y1300315D02*
X1206103Y1277020D01*
G01X1191262Y1300315D02*
X1206103Y1277020D01*
G01X1185361Y1324701D02*
X1184676Y1325776D01*
G01X1185361Y1324701D02*
X1184676Y1325776D01*
G01X1244752Y630285D02*
X1379213Y434766D01*
G01X1245967Y630814D02*
X1380138Y435716D01*
G01X1245967Y630814D02*
X1380138Y435716D01*
G01X1244752Y630285D02*
X1379213Y434766D01*
G01X1376172Y427047D02*
X1238960Y626341D01*
G01X1305314Y532258D02*
X1240175Y626870D01*
G01X1305314Y532258D02*
X1240175Y626870D01*
G01X1376172Y427047D02*
X1238960Y626341D01*
G01X1376172Y427047D02*
X1238960Y626341D01*
G01X1254295Y626936D02*
X1251868Y630774D01*
G01X1253089Y631277D02*
X1255317Y627754D01*
G01X1256134Y625098D02*
X1254295Y626936D01*
G01X1255317Y627754D02*
X1256673Y626398D01*
G01X1259137Y625098D02*
X1256134D01*
G01X1256673Y626398D02*
X1259137D01*
G01X1256673D02*
X1259137D01*
G01Y625098D02*
X1256134D01*
G01X1255317Y627754D02*
X1256673Y626398D01*
G01X1256134Y625098D02*
X1254295Y626936D01*
G01X1253089Y631277D02*
X1255317Y627754D01*
G01X1254295Y626936D02*
X1251868Y630774D01*
G01X1240175Y626870D02*
X1238974Y632288D01*
G01X1240175Y626870D02*
X1238974Y632288D01*
G01X1292825Y964166D02*
X1234840Y1056963D01*
G01X1293928Y964855D02*
X1236062Y1057463D01*
G01X1293928Y964855D02*
X1236062Y1057463D01*
G01X1292825Y964166D02*
X1234840Y1056963D01*
G01X1238255Y1015132D02*
X1302463Y914344D01*
G01X1239475Y1015637D02*
X1303560Y915043D01*
G01X1239475Y1015637D02*
X1303560Y915043D01*
G01X1238255Y1015132D02*
X1302463Y914344D01*
G01X1321167Y950432D02*
X1242931Y1073239D01*
G01X1400376Y828517D02*
X1244151Y1073744D01*
G01X1400376Y828517D02*
X1244151Y1073744D01*
G01X1400376Y828517D02*
X1244151Y1073744D01*
G01X1321167Y950432D02*
X1242931Y1073239D01*
G01X1238281Y1069416D02*
X1464315Y714891D01*
G01X1239501Y1069921D02*
X1465257Y715833D01*
G01X1239501Y1069921D02*
X1465257Y715833D01*
G01X1238281Y1069416D02*
X1464315Y714891D01*
G01X1256345Y1078501D02*
X1255843Y1078904D01*
G01X1257014Y1079632D02*
X1257609Y1079154D01*
G01X1256496Y1078379D02*
X1256345Y1078501D01*
G01X1257014Y1079632D02*
X1257609Y1079154D01*
G01X1257036Y1077947D02*
X1256496Y1078379D01*
G01X1257014Y1079632D02*
X1257609Y1079154D01*
G01X1259417Y1077854D02*
X1257301D01*
G01X1257609Y1079154D02*
X1259312D01*
G01X1257609D02*
X1259312D01*
G01X1259417Y1077854D02*
X1257301D01*
G01X1257014Y1079632D02*
X1257609Y1079154D01*
G01X1256345Y1078501D02*
X1255843Y1078904D01*
G01X1256496Y1078379D02*
X1256345Y1078501D01*
G01X1257036Y1077947D02*
X1256496Y1078379D01*
G01X1253639Y1072044D02*
X1251120Y1075998D01*
G01X1256177Y1070483D02*
X1252340Y1076504D01*
G01X1254877Y1070103D02*
X1253640Y1072045D01*
G01X1256177Y1070483D02*
X1252340Y1076504D01*
G01X1256998Y1066774D02*
X1254877Y1070103D01*
G01X1260013Y1064462D02*
X1256177Y1070482D01*
G01X1259071Y1063520D02*
X1256998Y1066774D01*
G01X1260013Y1064462D02*
X1256177Y1070482D01*
G01X1467660Y930630D02*
X1259071Y1063520D01*
G01X1364083Y998160D02*
X1260013Y1064462D01*
G01X1256177Y1070483D02*
X1252340Y1076504D01*
G01X1253639Y1072044D02*
X1251120Y1075998D01*
G01X1254877Y1070103D02*
X1253640Y1072045D01*
G01X1260013Y1064462D02*
X1256177Y1070482D01*
G01X1256998Y1066774D02*
X1254877Y1070103D01*
G01X1259071Y1063520D02*
X1256998Y1066774D01*
G01X1364083Y998160D02*
X1260013Y1064462D01*
G01X1467660Y930630D02*
X1259071Y1063520D01*
G01X1467660Y930630D02*
X1259071Y1063520D01*
G01X1235537Y1081788D02*
X1238281Y1069416D01*
G01X1238155Y1075996D02*
X1239501Y1069921D01*
G01X1237221Y1080204D02*
X1238155Y1075996D01*
G01X1236807Y1082071D02*
X1237221Y1080204D01*
G01X1238155Y1075996D02*
X1239501Y1069921D01*
G01X1235537Y1081788D02*
X1238281Y1069416D01*
G01X1237221Y1080204D02*
X1238155Y1075996D01*
G01X1235537Y1081788D02*
X1238281Y1069416D01*
G01X1236807Y1082071D02*
X1237221Y1080204D01*
G01X1235537Y1081788D02*
X1238281Y1069416D01*
G01X1275960Y1231580D02*
X1293229Y1206483D01*
G01X1276886Y1232530D02*
X1294151Y1207438D01*
G01X1276886Y1232530D02*
X1294151Y1207438D01*
G01X1275960Y1231580D02*
X1293229Y1206483D01*
G01X1377097Y427997D02*
X1305314Y532258D01*
G01X1377097Y427997D02*
X1305314Y532258D01*
G01X1328786Y873021D02*
X1345083Y802256D01*
G01X1315625Y893682D02*
X1328786Y873021D01*
G01X1316722Y894381D02*
X1330003Y873531D01*
G01X1328786Y873021D02*
X1345083Y802256D01*
G01X1316722Y894381D02*
X1330003Y873531D01*
G01X1315625Y893682D02*
X1328786Y873021D01*
G01X1399434Y827575D02*
X1321167Y950432D01*
G01X1399434Y827575D02*
X1321167Y950432D01*
G01X1353054Y870234D02*
X1301318Y953029D01*
G01X1319923Y920800D02*
X1307606Y940512D01*
G01X1353054Y870234D02*
X1301318Y953029D01*
G01X1322388Y916856D02*
X1319923Y920800D01*
G01X1353054Y870234D02*
X1301318Y953029D01*
G01X1351951Y869545D02*
X1322388Y916856D01*
G01X1353054Y870234D02*
X1301318Y953029D01*
G01X1353054Y870234D02*
X1301318Y953029D01*
G01X1319923Y920800D02*
X1307606Y940512D01*
G01X1322388Y916856D02*
X1319923Y920800D01*
G01X1351951Y869545D02*
X1322388Y916856D01*
G01X1302463Y914344D02*
X1315625Y893682D01*
G01X1303560Y915043D02*
X1316722Y894381D01*
G01X1303560Y915043D02*
X1316722Y894381D01*
G01X1302463Y914344D02*
X1315625Y893682D01*
G01X1303910Y946427D02*
X1292825Y964166D01*
G01X1301318Y953029D02*
X1293928Y964855D01*
G01X1307605Y940512D02*
X1303910Y946427D01*
G01X1301318Y953029D02*
X1293928Y964855D01*
G01X1303910Y946427D02*
X1292825Y964166D01*
G01X1307605Y940512D02*
X1303910Y946427D01*
G01X1326594Y1099447D02*
X1377749Y1077854D01*
G01X1327242Y1100586D02*
X1365320Y1084512D01*
G01X1297329Y1121004D02*
X1326594Y1099447D01*
G01X1298296Y1121908D02*
X1327242Y1100586D01*
G01X1326594Y1099447D02*
X1377749Y1077854D01*
G01X1327242Y1100586D02*
X1365320Y1084512D01*
G01X1326594Y1099447D02*
X1377749Y1077854D01*
G01X1298296Y1121908D02*
X1327242Y1100586D01*
G01X1297329Y1121004D02*
X1326594Y1099447D01*
G01X1460011Y1187777D02*
X1319357Y1218961D01*
G01X1460533Y1188993D02*
X1319862Y1220181D01*
G01X1460533Y1188993D02*
X1319862Y1220181D01*
G01X1460011Y1187777D02*
X1319357Y1218961D01*
G01X1293229Y1206483D02*
X1490529Y1080790D01*
G01X1294151Y1207438D02*
X1491035Y1082010D01*
G01X1294151Y1207438D02*
X1491035Y1082010D01*
G01X1293229Y1206483D02*
X1490529Y1080790D01*
G01X1539557Y320946D02*
X1376172Y427047D01*
G01X1540321Y322001D02*
X1377097Y427997D01*
G01X1540321Y322001D02*
X1377097Y427997D01*
G01X1539557Y320946D02*
X1376172Y427047D01*
G01X1377058Y624144D02*
X1381543Y625098D01*
G01X1377058Y625474D02*
X1381406Y626398D01*
G01X1369753Y625699D02*
X1377058Y624144D01*
G01X1362987Y628469D02*
X1377058Y625474D01*
G01X1362480Y627247D02*
X1369753Y625699D01*
G01X1362987Y628469D02*
X1377058Y625474D01*
G01X1352311Y633853D02*
X1362480Y627247D01*
G01X1353251Y634794D02*
X1362987Y628469D01*
G01X1348756Y639314D02*
X1352311Y633853D01*
G01X1349978Y639821D02*
X1353251Y634794D01*
G01X1345274Y655706D02*
X1348756Y639314D01*
G01X1346604Y655706D02*
X1349978Y639821D01*
G01X1377058Y625474D02*
X1381406Y626398D01*
G01X1377058Y624144D02*
X1381543Y625098D01*
G01X1362987Y628469D02*
X1377058Y625474D01*
G01X1369753Y625699D02*
X1377058Y624144D01*
G01X1362480Y627247D02*
X1369753Y625699D01*
G01X1353251Y634794D02*
X1362987Y628469D01*
G01X1352311Y633853D02*
X1362480Y627247D01*
G01X1349978Y639821D02*
X1353251Y634794D01*
G01X1348756Y639314D02*
X1352311Y633853D01*
G01X1346604Y655706D02*
X1349978Y639821D01*
G01X1345274Y655706D02*
X1348756Y639314D01*
G01X1352070Y687686D02*
X1345274Y655706D01*
G01X1353342Y687416D02*
X1346604Y655706D01*
G01X1353367Y693789D02*
X1352070Y687686D01*
G01X1362710Y731505D02*
X1353342Y687416D01*
G01X1353785Y695761D02*
X1353367Y693789D01*
G01X1362710Y731505D02*
X1353342Y687416D01*
G01X1354397Y698637D02*
X1353785Y695761D01*
G01X1362710Y731505D02*
X1353342Y687416D01*
G01X1362710Y731505D02*
X1353342Y687416D01*
G01X1362710Y731505D02*
X1353342Y687416D01*
G01D02*
X1346604Y655706D01*
G01X1352070Y687686D02*
X1345274Y655706D01*
G01X1362710Y731505D02*
X1353342Y687416D01*
G01X1353367Y693789D02*
X1352070Y687686D01*
G01X1353785Y695761D02*
X1353367Y693789D01*
G01X1354397Y698637D02*
X1353785Y695761D01*
G01X1356724Y709589D02*
X1354397Y698637D01*
G01X1361378Y731494D02*
X1356724Y709590D01*
G01X1357338Y749042D02*
X1361378Y731494D01*
G01X1354499Y767166D02*
X1362710Y731505D01*
G01X1356724Y709589D02*
X1354397Y698637D01*
G01X1361378Y731494D02*
X1356724Y709590D01*
G01X1354499Y767166D02*
X1362710Y731505D01*
G01X1357338Y749042D02*
X1361378Y731494D01*
G01X1330003Y873531D02*
X1354499Y767166D01*
G01X1330003Y873531D02*
X1354499Y767166D01*
G01X1470204Y680301D02*
X1351950Y869545D01*
G01X1471307Y680990D02*
X1353054Y870234D01*
G01X1471307Y680990D02*
X1353054Y870234D01*
G01X1470204Y680301D02*
X1351950Y869545D01*
G01X1468156Y931857D02*
X1364083Y998160D01*
G01X1468156Y931857D02*
X1364083Y998160D01*
G01X1377749Y1077854D02*
X1383542D01*
G01X1365320Y1084512D02*
X1378013Y1079154D01*
G01X1377749Y1077854D02*
X1383542D01*
G01X1365320Y1084512D02*
X1378013Y1079154D01*
G01X1398501Y1311581D02*
X1365599Y1318876D01*
G01X1398501Y1311581D02*
X1365599Y1318876D01*
G01X1380138Y435716D02*
X1565396Y315401D01*
G01X1379213Y434766D02*
X1472058Y374468D01*
G01X1380138Y435716D02*
X1565396Y315401D01*
G01X1380138Y435716D02*
X1565396Y315401D01*
G01X1379213Y434766D02*
X1472058Y374468D01*
G01X1381543Y625098D02*
X1383542D01*
G01X1381406Y626398D02*
X1383542D01*
G01X1381406D02*
X1383542D01*
G01X1381543Y625098D02*
X1383542D01*
G01X1549978Y731669D02*
X1399434Y827575D01*
G01X1699891Y637708D02*
X1400376Y828517D01*
G01X1699891Y637708D02*
X1400376Y828517D01*
G01X1699891Y637708D02*
X1400376Y828517D01*
G01X1699891Y637708D02*
X1400376Y828517D01*
G01X1699891Y637708D02*
X1400376Y828517D01*
G01X1549978Y731669D02*
X1399434Y827575D01*
G01X1378013Y1079154D02*
X1383542D01*
G01X1378013D02*
X1383542D01*
G01X1402320Y1309402D02*
X1401076Y1309678D01*
G01X1416466Y1307598D02*
X1398501Y1311581D01*
G01X1406421Y1308493D02*
X1405176Y1308769D01*
G01X1416466Y1307598D02*
X1398501Y1311581D01*
G01X1416003Y1306369D02*
X1409277Y1307860D01*
G01X1416466Y1307598D02*
X1398501Y1311581D01*
G01X1804633Y1093129D02*
X1416003Y1306369D01*
G01X1805096Y1094358D02*
X1416466Y1307598D01*
G01D02*
X1398501Y1311581D01*
G01X1402320Y1309402D02*
X1401076Y1309678D01*
G01X1406421Y1308493D02*
X1405176Y1308769D01*
G01X1416003Y1306369D02*
X1409277Y1307860D01*
G01X1805096Y1094358D02*
X1416466Y1307598D01*
G01X1804633Y1093129D02*
X1416003Y1306369D01*
G01X1404958Y1302760D02*
X1403713Y1303036D01*
G01X1409058Y1301851D02*
X1407814Y1302127D01*
G01X1419446Y1299548D02*
X1411914Y1301218D01*
G01X1689692Y1104702D02*
X1419446Y1299548D01*
G01X1690343Y1105836D02*
X1419989Y1300760D01*
G01X1404958Y1302760D02*
X1403713Y1303036D01*
G01X1409058Y1301851D02*
X1407814Y1302127D01*
G01X1419446Y1299548D02*
X1411914Y1301218D01*
G01X1690343Y1105836D02*
X1419989Y1300760D01*
G01X1689692Y1104702D02*
X1419446Y1299548D01*
G01X1528323Y233467D02*
X1469083Y281132D01*
G01X1588232Y186932D02*
X1470047Y282026D01*
G01X1588232Y186932D02*
X1470047Y282026D01*
G01X1588232Y186932D02*
X1470047Y282026D01*
G01X1528323Y233467D02*
X1469083Y281132D01*
G01X1491493Y224025D02*
X1474351Y263866D01*
G01X1491493Y224025D02*
X1474351Y263866D01*
G01X1491493Y224025D02*
X1474351Y263866D01*
G01X1472058Y374468D02*
X1564830Y314217D01*
G01X1472058Y374468D02*
X1564830Y314217D01*
G01X1504149Y625977D02*
X1470204Y680301D01*
G01X1505094Y626920D02*
X1471307Y680991D01*
G01X1505094Y626920D02*
X1471307Y680991D01*
G01X1504149Y625977D02*
X1470204Y680301D01*
G01X1464315Y714891D02*
X1596137Y630910D01*
G01X1465257Y715833D02*
X1596642Y632130D01*
G01X1465257Y715833D02*
X1596642Y632130D01*
G01X1464315Y714891D02*
X1596137Y630910D01*
G01X1692298Y884937D02*
X1467660Y930630D01*
G01X1692798Y886163D02*
X1468156Y931857D01*
G01X1692798Y886163D02*
X1468156Y931857D01*
G01X1692298Y884937D02*
X1467660Y930630D01*
G01X1614487Y1083577D02*
X1460011Y1187777D01*
G01X1614487Y1083577D02*
X1460011Y1187777D01*
G01X1615091Y1084739D02*
X1460533Y1188993D01*
G01X1615091Y1084739D02*
X1460533Y1188993D01*
G01X1508638Y184184D02*
X1491493Y224025D01*
G01X1509938Y184452D02*
X1492688Y224539D01*
G01X1508638Y182208D02*
Y184184D01*
G01X1509938Y182260D02*
Y184452D01*
G01D02*
X1492688Y224539D01*
G01X1508638Y184184D02*
X1491493Y224025D01*
G01X1509938Y182260D02*
Y184452D01*
G01X1508638Y182208D02*
Y184184D01*
G01X1484117Y244458D02*
X1475495Y264497D01*
G01X1492688Y224539D02*
X1484117Y244458D01*
G01D02*
X1475495Y264497D01*
G01X1492688Y224539D02*
X1484117Y244458D01*
G01X1505550Y625098D02*
X1504149Y625977D01*
G01X1505925Y626398D02*
X1505094Y626920D01*
G01X1507754Y625098D02*
X1505550D01*
G01X1507754Y626398D02*
X1505925D01*
G01D02*
X1505094Y626920D01*
G01X1505550Y625098D02*
X1504149Y625977D01*
G01X1507754Y626398D02*
X1505925D01*
G01X1507754Y625098D02*
X1505550D01*
G01X1503757Y1077854D02*
X1507754D01*
G01X1503900Y1079154D02*
X1507754D01*
G01X1490529Y1080790D02*
X1503757Y1077854D01*
G01X1491035Y1082010D02*
X1503899Y1079155D01*
G01X1503900Y1079154D02*
X1507754D01*
G01X1503757Y1077854D02*
X1507754D01*
G01X1491035Y1082010D02*
X1503899Y1079155D01*
G01X1490529Y1080790D02*
X1503757Y1077854D01*
G01X1587602Y185770D02*
X1528324Y233466D01*
G01X1587602Y185770D02*
X1528324Y233466D01*
G01X1705222Y187652D02*
X1539557Y320946D01*
G01X1705852Y188814D02*
X1540321Y322001D01*
G01X1705852Y188814D02*
X1540321Y322001D01*
G01X1705222Y187652D02*
X1539557Y320946D01*
G01X1564830Y314217D02*
X1745624Y255209D01*
G01X1565396Y315401D02*
X1746254Y256371D01*
G01X1565396Y315401D02*
X1746254Y256371D01*
G01X1564830Y314217D02*
X1745624Y255209D01*
G01X1587256Y707921D02*
X1549978Y731669D01*
G01X1587256Y707921D02*
X1549978Y731669D01*
G01X1628744Y172342D02*
X1587602Y185770D01*
G01X1628951Y173642D02*
X1588232Y186932D01*
G01X1628951Y173642D02*
X1588232Y186932D01*
G01X1628744Y172342D02*
X1587602Y185770D01*
G01X1596137Y630910D02*
X1622348Y625098D01*
G01X1596642Y632130D02*
X1622491Y626398D01*
G01X1596642Y632130D02*
X1622491Y626398D01*
G01X1596137Y630910D02*
X1622348Y625098D01*
G01X1699279Y636555D02*
X1587257Y707921D01*
G01X1699279Y636555D02*
X1587257Y707921D01*
G01D02*
X1587256D01*
G01X1587257D02*
X1587256D01*
G01X1629472Y1077854D02*
X1614487Y1083577D01*
G01X1629472Y1077854D02*
X1614487Y1083577D01*
G01X1629712Y1079154D02*
X1615091Y1084739D01*
G01X1629712Y1079154D02*
X1615091Y1084739D01*
G01X1631967Y172342D02*
X1628744D01*
G01X1631967Y173642D02*
X1628951D01*
G01X1631967D02*
X1628951D01*
G01X1631967Y172342D02*
X1628744D01*
G01X1622348Y625098D02*
X1631967D01*
G01X1622491Y626398D02*
X1631967D01*
G01X1622491D02*
X1631967D01*
G01X1622348Y625098D02*
X1631967D01*
G01Y1077854D02*
X1629472D01*
G01X1631967Y1079154D02*
X1629712D01*
G01X1631967D02*
X1629712D01*
G01X1631967Y1077854D02*
X1629472D01*
G01X1752127Y172342D02*
X1705222Y187652D01*
G01X1729093Y181228D02*
X1705852Y188814D01*
G01X1729093Y181228D02*
X1705852Y188814D01*
G01X1752127Y172342D02*
X1705222Y187652D01*
G01X1752127Y172342D02*
X1705222Y187652D01*
G01X1725783Y625098D02*
X1699279Y636555D01*
G01X1726052Y626398D02*
X1699891Y637708D01*
G01X1726052Y626398D02*
X1699891Y637708D01*
G01X1725783Y625098D02*
X1699279Y636555D01*
G01X1708062Y874758D02*
X1692298Y884937D01*
G01X1708768Y875851D02*
X1692798Y886163D01*
G01X1723566Y864746D02*
X1708062Y874758D01*
G01X1718169Y869780D02*
X1708768Y875851D01*
G01D02*
X1692798Y886163D01*
G01X1708062Y874758D02*
X1692298Y884937D01*
G01X1718169Y869780D02*
X1708768Y875851D01*
G01X1723566Y864746D02*
X1708062Y874758D01*
G01X1723566Y864746D02*
X1708062Y874758D01*
G01X1750129Y1077854D02*
X1689692Y1104702D01*
G01X1750405Y1079154D02*
X1690343Y1105836D01*
G01X1750405Y1079154D02*
X1690343Y1105836D01*
G01X1750129Y1077854D02*
X1689692Y1104702D01*
G01X1752334Y173642D02*
X1729093Y181229D01*
G01X1756179Y172342D02*
X1752127D01*
G01X1756179Y173642D02*
X1752334D01*
G01D02*
X1729093Y181229D01*
G01X1756179Y173642D02*
X1752334D01*
G01X1756179Y172342D02*
X1752127D01*
G01X1746254Y256371D02*
X1823739Y194028D01*
G01X1745624Y255209D02*
X1764895Y239704D01*
G01X1746254Y256371D02*
X1823739Y194028D01*
G01X1746254Y256371D02*
X1823739Y194028D01*
G01X1745624Y255209D02*
X1764895Y239704D01*
G01X1731179Y625098D02*
X1725783D01*
G01X1731179Y626398D02*
X1726052D01*
G01X1731179D02*
X1726052D01*
G01X1731179Y625098D02*
X1725783D01*
G01X1782072Y764332D02*
X1723566Y864746D01*
G01X1783288Y764828D02*
X1724533Y865670D01*
G01X1783288Y764828D02*
X1724533Y865670D01*
G01X1782072Y764332D02*
X1723566Y864746D01*
G01X1724533Y865670D02*
X1718169Y869780D01*
G01X1724533Y865670D02*
X1718169Y869780D01*
G01X1756179Y1077854D02*
X1750129D01*
G01X1756179Y1079154D02*
X1750405D01*
G01X1756179D02*
X1750405D01*
G01X1756179Y1077854D02*
X1750129D01*
G01X1764896Y239703D02*
X1823085Y192885D01*
G01X1764896Y239703D02*
X1823085Y192885D01*
G01X1803597Y679104D02*
X1782072Y764332D01*
G01X1804817Y679585D02*
X1783288Y764828D01*
G01X1811786Y664256D02*
X1803597Y679104D01*
G01X1821033Y650182D02*
X1804817Y679585D01*
G01X1820017Y649330D02*
X1811786Y664256D01*
G01X1821033Y650182D02*
X1804817Y679585D01*
G01D02*
X1783288Y764828D01*
G01X1803597Y679104D02*
X1782072Y764332D01*
G01X1821033Y650182D02*
X1804817Y679585D01*
G01X1811786Y664256D02*
X1803597Y679104D01*
G01X1820017Y649330D02*
X1811786Y664256D01*
G01X1873535Y1077854D02*
X1804633Y1093129D01*
G01X1873678Y1079154D02*
X1805096Y1094358D01*
G01X1873678Y1079154D02*
X1805096Y1094358D01*
G01X1873535Y1077854D02*
X1804633Y1093129D01*
G01X1823085Y192885D02*
X1877350Y172342D01*
G01X1823739Y194028D02*
X1877588Y173642D01*
G01X1823739Y194028D02*
X1877588Y173642D01*
G01X1823085Y192885D02*
X1877350Y172342D01*
G01X1840447Y632833D02*
X1820017Y649330D01*
G01X1841033Y634031D02*
X1821033Y650182D01*
G01X1873401Y625098D02*
X1840447Y632833D01*
G01X1873552Y626398D02*
X1841033Y634031D01*
G01D02*
X1821033Y650182D01*
G01X1840447Y632833D02*
X1820017Y649330D01*
G01X1873552Y626398D02*
X1841033Y634031D01*
G01X1873401Y625098D02*
X1840447Y632833D01*
G01X1877350Y172342D02*
X1880392D01*
G01X1877588Y173642D02*
X1880392D01*
G01X1877588D02*
X1880392D01*
G01X1877350Y172342D02*
X1880392D01*
G01Y625098D02*
X1873401D01*
G01X1880392Y626398D02*
X1873552D01*
G01X1880392D02*
X1873552D01*
G01X1880392Y625098D02*
X1873401D01*
G01X1880392Y1077854D02*
X1873535D01*
G01X1880392Y1079154D02*
X1873678D01*
G01X1880392D02*
X1873678D01*
G01X1880392Y1077854D02*
X1873535D01*
M02*
